(kicad_sch
	(version 20250114)
	(generator "eeschema")
	(generator_version "9.0")
	(paper "A3")
	(title_block
		(title "Kintex 410T devboard")
		(date "2024-04-03")
		(rev "1.1.2")
	)
	(text "Power over Ethernet"
		(exclude_from_sim no)
		(at 13.335 170.815 0)
		(effects
			(font
				(size 1.27 1.27)
				(thickness 0.4)
				(bold yes)
			)
			(justify left bottom)
		)
	)
	(text "Power MUX/selection"
		(exclude_from_sim no)
		(at 250.825 18.415 0)
		(effects
			(font
				(size 1.27 1.27)
				(thickness 0.4)
				(bold yes)
			)
			(justify left bottom)
		)
	)
	(text "PD enabled\n\nPDO2 negotiated\n\nPDO3 negotiated"
		(exclude_from_sim no)
		(at 24.13 161.925 0)
		(effects
			(font
				(size 1.27 1.27)
			)
			(justify left bottom)
		)
	)
	(text "PD LED COLOR CODE"
		(exclude_from_sim no)
		(at 15.24 150.495 0)
		(effects
			(font
				(size 1.27 1.27)
				(thickness 0.3)
				(bold yes)
			)
			(justify left bottom)
		)
	)
	(text "RED\n\nBLUE\n\nGREEN"
		(exclude_from_sim no)
		(at 15.24 161.925 0)
		(effects
			(font
				(size 1.27 1.27)
			)
			(justify left bottom)
		)
	)
	(text "DC Input"
		(exclude_from_sim no)
		(at 13.335 17.78 0)
		(effects
			(font
				(size 1.27 1.27)
				(thickness 0.4)
				(bold yes)
			)
			(justify left bottom)
		)
	)
	(text "USB-C Power Delivery"
		(exclude_from_sim no)
		(at 12.7 73.025 0)
		(effects
			(font
				(size 1.27 1.27)
				(thickness 0.4)
				(bold yes)
			)
			(justify left bottom)
		)
	)
	(junction
		(at 39.37 39.37)
		(diameter 0)
		(color 0 0 0 0)
	)
	(junction
		(at 152.4 256.54)
		(diameter 0)
		(color 0 0 0 0)
	)
	(junction
		(at 184.15 256.54)
		(diameter 0)
		(color 0 0 0 0)
	)
	(junction
		(at 128.905 96.52)
		(diameter 0)
		(color 0 0 0 0)
	)
	(junction
		(at 144.78 190.5)
		(diameter 0)
		(color 0 0 0 0)
	)
	(junction
		(at 313.69 83.82)
		(diameter 0)
		(color 0 0 0 0)
	)
	(junction
		(at 74.93 236.22)
		(diameter 0)
		(color 0 0 0 0)
	)
	(junction
		(at 182.88 83.82)
		(diameter 0)
		(color 0 0 0 0)
	)
	(junction
		(at 166.37 190.5)
		(diameter 0)
		(color 0 0 0 0)
	)
	(junction
		(at 313.69 54.61)
		(diameter 0)
		(color 0 0 0 0)
	)
	(junction
		(at 313.69 34.29)
		(diameter 0)
		(color 0 0 0 0)
	)
	(junction
		(at 177.8 269.24)
		(diameter 0)
		(color 0 0 0 0)
	)
	(junction
		(at 313.69 200.66)
		(diameter 0)
		(color 0 0 0 0)
	)
	(junction
		(at 128.905 83.82)
		(diameter 0)
		(color 0 0 0 0)
	)
	(junction
		(at 120.65 256.54)
		(diameter 0)
		(color 0 0 0 0)
	)
	(junction
		(at 198.12 190.5)
		(diameter 0)
		(color 0 0 0 0)
	)
	(junction
		(at 118.11 264.16)
		(diameter 0)
		(color 0 0 0 0)
	)
	(junction
		(at 63.5 34.29)
		(diameter 0)
		(color 0 0 0 0)
	)
	(junction
		(at 313.69 210.82)
		(diameter 0)
		(color 0 0 0 0)
	)
	(junction
		(at 125.73 256.54)
		(diameter 0)
		(color 0 0 0 0)
	)
	(junction
		(at 195.58 223.52)
		(diameter 0)
		(color 0 0 0 0)
	)
	(junction
		(at 161.29 83.82)
		(diameter 0)
		(color 0 0 0 0)
	)
	(junction
		(at 217.17 205.74)
		(diameter 0)
		(color 0 0 0 0)
	)
	(junction
		(at 93.98 83.82)
		(diameter 0)
		(color 0 0 0 0)
	)
	(junction
		(at 39.37 44.45)
		(diameter 0)
		(color 0 0 0 0)
	)
	(junction
		(at 350.52 34.29)
		(diameter 0)
		(color 0 0 0 0)
	)
	(junction
		(at 224.79 190.5)
		(diameter 0)
		(color 0 0 0 0)
	)
	(junction
		(at 76.2 34.29)
		(diameter 0)
		(color 0 0 0 0)
	)
	(junction
		(at 392.43 83.82)
		(diameter 0)
		(color 0 0 0 0)
	)
	(junction
		(at 115.57 190.5)
		(diameter 0)
		(color 0 0 0 0)
	)
	(junction
		(at 120.65 228.6)
		(diameter 0)
		(color 0 0 0 0)
	)
	(junction
		(at 112.395 96.52)
		(diameter 0)
		(color 0 0 0 0)
	)
	(junction
		(at 144.78 256.54)
		(diameter 0)
		(color 0 0 0 0)
	)
	(junction
		(at 139.065 96.52)
		(diameter 0)
		(color 0 0 0 0)
	)
	(junction
		(at 313.69 99.06)
		(diameter 0)
		(color 0 0 0 0)
	)
	(junction
		(at 146.05 157.48)
		(diameter 0)
		(color 0 0 0 0)
	)
	(junction
		(at 313.69 49.53)
		(diameter 0)
		(color 0 0 0 0)
	)
	(junction
		(at 313.69 44.45)
		(diameter 0)
		(color 0 0 0 0)
	)
	(junction
		(at 74.93 190.5)
		(diameter 0)
		(color 0 0 0 0)
	)
	(junction
		(at 125.73 228.6)
		(diameter 0)
		(color 0 0 0 0)
	)
	(junction
		(at 350.52 83.82)
		(diameter 0)
		(color 0 0 0 0)
	)
	(junction
		(at 217.17 190.5)
		(diameter 0)
		(color 0 0 0 0)
	)
	(junction
		(at 142.24 256.54)
		(diameter 0)
		(color 0 0 0 0)
	)
	(junction
		(at 346.71 190.5)
		(diameter 0)
		(color 0 0 0 0)
	)
	(junction
		(at 158.75 190.5)
		(diameter 0)
		(color 0 0 0 0)
	)
	(junction
		(at 313.69 190.5)
		(diameter 0)
		(color 0 0 0 0)
	)
	(junction
		(at 198.12 205.74)
		(diameter 0)
		(color 0 0 0 0)
	)
	(junction
		(at 161.29 96.52)
		(diameter 0)
		(color 0 0 0 0)
	)
	(junction
		(at 111.76 156.21)
		(diameter 0)
		(color 0 0 0 0)
	)
	(junction
		(at 195.58 256.54)
		(diameter 0)
		(color 0 0 0 0)
	)
	(junction
		(at 209.55 190.5)
		(diameter 0)
		(color 0 0 0 0)
	)
	(junction
		(at 209.55 205.74)
		(diameter 0)
		(color 0 0 0 0)
	)
	(junction
		(at 313.69 205.74)
		(diameter 0)
		(color 0 0 0 0)
	)
	(junction
		(at 90.17 83.82)
		(diameter 0)
		(color 0 0 0 0)
	)
	(junction
		(at 392.43 34.29)
		(diameter 0)
		(color 0 0 0 0)
	)
	(junction
		(at 52.07 256.54)
		(diameter 0)
		(color 0 0 0 0)
	)
	(junction
		(at 350.52 190.5)
		(diameter 0)
		(color 0 0 0 0)
	)
	(junction
		(at 247.65 190.5)
		(diameter 0)
		(color 0 0 0 0)
	)
	(junction
		(at 111.76 146.05)
		(diameter 0)
		(color 0 0 0 0)
	)
	(junction
		(at 118.11 259.08)
		(diameter 0)
		(color 0 0 0 0)
	)
	(junction
		(at 106.68 128.27)
		(diameter 0)
		(color 0 0 0 0)
	)
	(junction
		(at 152.4 254)
		(diameter 0)
		(color 0 0 0 0)
	)
	(junction
		(at 137.16 190.5)
		(diameter 0)
		(color 0 0 0 0)
	)
	(junction
		(at 172.72 83.82)
		(diameter 0)
		(color 0 0 0 0)
	)
	(junction
		(at 346.71 83.82)
		(diameter 0)
		(color 0 0 0 0)
	)
	(junction
		(at 39.37 54.61)
		(diameter 0)
		(color 0 0 0 0)
	)
	(junction
		(at 52.07 210.82)
		(diameter 0)
		(color 0 0 0 0)
	)
	(junction
		(at 111.76 143.51)
		(diameter 0)
		(color 0 0 0 0)
	)
	(junction
		(at 148.59 228.6)
		(diameter 0)
		(color 0 0 0 0)
	)
	(junction
		(at 313.69 104.14)
		(diameter 0)
		(color 0 0 0 0)
	)
	(junction
		(at 118.11 261.62)
		(diameter 0)
		(color 0 0 0 0)
	)
	(junction
		(at 109.22 190.5)
		(diameter 0)
		(color 0 0 0 0)
	)
	(junction
		(at 346.71 34.29)
		(diameter 0)
		(color 0 0 0 0)
	)
	(junction
		(at 313.69 93.98)
		(diameter 0)
		(color 0 0 0 0)
	)
	(junction
		(at 224.79 205.74)
		(diameter 0)
		(color 0 0 0 0)
	)
	(junction
		(at 151.13 190.5)
		(diameter 0)
		(color 0 0 0 0)
	)
	(no_connect
		(at 332.74 49.53)
	)
	(no_connect
		(at 175.26 236.22)
	)
	(no_connect
		(at 332.74 205.74)
	)
	(no_connect
		(at 175.26 238.76)
	)
	(no_connect
		(at 144.78 125.73)
	)
	(no_connect
		(at 332.74 99.06)
	)
	(no_connect
		(at 175.26 261.62)
	)
	(no_connect
		(at 153.67 269.24)
	)
	(no_connect
		(at 205.74 198.12)
	)
	(no_connect
		(at 144.78 123.19)
	)
	(no_connect
		(at 144.78 120.65)
	)
	(no_connect
		(at 144.78 128.27)
	)
	(no_connect
		(at 175.26 241.3)
	)
	(bus_entry
		(at 36.83 215.9)
		(size -1.27 -1.27)
		(stroke
			(width 0)
			(type default)
		)
	)
	(bus_entry
		(at 36.83 251.46)
		(size -1.27 -1.27)
		(stroke
			(width 0)
			(type default)
		)
	)
	(bus_entry
		(at 90.17 133.35)
		(size -1.27 -1.27)
		(stroke
			(width 0)
			(type default)
		)
	)
	(bus_entry
		(at 88.9 123.19)
		(size 1.27 0)
		(stroke
			(width 0)
			(type default)
		)
	)
	(bus_entry
		(at 36.83 195.58)
		(size -1.27 -1.27)
		(stroke
			(width 0)
			(type default)
		)
	)
	(bus_entry
		(at 36.83 231.14)
		(size -1.27 -1.27)
		(stroke
			(width 0)
			(type default)
		)
	)
	(bus_entry
		(at 64.77 146.05)
		(size -1.27 -1.27)
		(stroke
			(width 0)
			(type default)
		)
	)
	(bus_entry
		(at 36.83 261.62)
		(size -1.27 -1.27)
		(stroke
			(width 0)
			(type default)
		)
	)
	(bus_entry
		(at 88.9 118.11)
		(size 1.27 0)
		(stroke
			(width 0)
			(type default)
		)
	)
	(bus_entry
		(at 36.83 205.74)
		(size -1.27 -1.27)
		(stroke
			(width 0)
			(type default)
		)
	)
	(bus_entry
		(at 88.9 134.62)
		(size 1.27 1.27)
		(stroke
			(width 0)
			(type default)
		)
	)
	(bus_entry
		(at 64.77 83.82)
		(size -1.27 -1.27)
		(stroke
			(width 0)
			(type default)
		)
	)
	(bus_entry
		(at 36.83 241.3)
		(size -1.27 -1.27)
		(stroke
			(width 0)
			(type default)
		)
	)
	(bus_entry
		(at 64.77 143.51)
		(size -1.27 -1.27)
		(stroke
			(width 0)
			(type default)
		)
	)
	(bus_entry
		(at 36.83 185.42)
		(size -1.27 -1.27)
		(stroke
			(width 0)
			(type default)
		)
	)
	(polyline
		(pts
			(xy 41.91 147.32) (xy 41.91 162.56)
		)
		(stroke
			(width 0)
			(type solid)
		)
	)
	(wire
		(pts
			(xy 175.26 205.74) (xy 176.53 205.74)
		)
		(stroke
			(width 0)
			(type default)
		)
	)
	(wire
		(pts
			(xy 144.78 246.38) (xy 144.78 248.92)
		)
		(stroke
			(width 0)
			(type default)
		)
	)
	(wire
		(pts
			(xy 147.955 96.52) (xy 151.765 96.52)
		)
		(stroke
			(width 0)
			(type default)
		)
	)
	(wire
		(pts
			(xy 111.76 156.21) (xy 114.3 156.21)
		)
		(stroke
			(width 0)
			(type default)
		)
	)
	(wire
		(pts
			(xy 144.78 256.54) (xy 142.24 256.54)
		)
		(stroke
			(width 0)
			(type default)
		)
	)
	(wire
		(pts
			(xy 52.07 236.22) (xy 52.07 256.54)
		)
		(stroke
			(width 0)
			(type default)
		)
	)
	(wire
		(pts
			(xy 184.15 256.54) (xy 184.15 260.35)
		)
		(stroke
			(width 0)
			(type default)
		)
	)
	(bus
		(pts
			(xy 87.63 129.54) (xy 86.36 129.54)
		)
		(stroke
			(width 0)
			(type default)
		)
	)
	(wire
		(pts
			(xy 303.53 200.66) (xy 303.53 203.2)
		)
		(stroke
			(width 0)
			(type default)
		)
	)
	(wire
		(pts
			(xy 217.17 190.5) (xy 224.79 190.5)
		)
		(stroke
			(width 0)
			(type default)
		)
	)
	(wire
		(pts
			(xy 120.65 245.11) (xy 120.65 256.54)
		)
		(stroke
			(width 0)
			(type default)
		)
	)
	(wire
		(pts
			(xy 52.07 210.82) (xy 52.07 219.71)
		)
		(stroke
			(width 0)
			(type default)
		)
	)
	(wire
		(pts
			(xy 116.205 83.82) (xy 128.905 83.82)
		)
		(stroke
			(width 0)
			(type default)
		)
	)
	(wire
		(pts
			(xy 52.07 256.54) (xy 52.07 264.16)
		)
		(stroke
			(width 0)
			(type default)
		)
	)
	(wire
		(pts
			(xy 217.17 205.74) (xy 224.79 205.74)
		)
		(stroke
			(width 0)
			(type default)
		)
	)
	(wire
		(pts
			(xy 128.905 96.52) (xy 139.065 96.52)
		)
		(stroke
			(width 0)
			(type default)
		)
	)
	(wire
		(pts
			(xy 137.16 190.5) (xy 137.16 193.04)
		)
		(stroke
			(width 0)
			(type default)
		)
	)
	(wire
		(pts
			(xy 36.83 205.74) (xy 53.34 205.74)
		)
		(stroke
			(width 0)
			(type default)
		)
	)
	(wire
		(pts
			(xy 314.96 96.52) (xy 313.69 96.52)
		)
		(stroke
			(width 0)
			(type default)
		)
	)
	(wire
		(pts
			(xy 205.74 198.12) (xy 204.47 198.12)
		)
		(stroke
			(width 0)
			(type default)
		)
	)
	(wire
		(pts
			(xy 313.69 71.12) (xy 334.01 71.12)
		)
		(stroke
			(width 0)
			(type default)
		)
	)
	(wire
		(pts
			(xy 313.69 21.59) (xy 313.69 34.29)
		)
		(stroke
			(width 0)
			(type default)
		)
	)
	(wire
		(pts
			(xy 74.93 236.22) (xy 78.74 236.22)
		)
		(stroke
			(width 0)
			(type default)
		)
	)
	(wire
		(pts
			(xy 93.98 107.95) (xy 111.125 107.95)
		)
		(stroke
			(width 0)
			(type default)
		)
	)
	(wire
		(pts
			(xy 111.76 153.67) (xy 114.3 153.67)
		)
		(stroke
			(width 0)
			(type default)
		)
	)
	(wire
		(pts
			(xy 339.09 46.99) (xy 339.09 41.91)
		)
		(stroke
			(width 0)
			(type default)
		)
	)
	(wire
		(pts
			(xy 196.85 205.74) (xy 198.12 205.74)
		)
		(stroke
			(width 0)
			(type default)
		)
	)
	(wire
		(pts
			(xy 90.17 96.52) (xy 90.17 97.79)
		)
		(stroke
			(width 0)
			(type default)
		)
	)
	(wire
		(pts
			(xy 195.58 256.54) (xy 196.85 256.54)
		)
		(stroke
			(width 0)
			(type default)
		)
	)
	(wire
		(pts
			(xy 313.69 210.82) (xy 313.69 212.09)
		)
		(stroke
			(width 0)
			(type default)
		)
	)
	(wire
		(pts
			(xy 303.53 104.14) (xy 313.69 104.14)
		)
		(stroke
			(width 0)
			(type default)
		)
	)
	(wire
		(pts
			(xy 39.37 54.61) (xy 39.37 55.88)
		)
		(stroke
			(width 0)
			(type default)
		)
	)
	(wire
		(pts
			(xy 172.72 123.19) (xy 172.72 125.73)
		)
		(stroke
			(width 0)
			(type default)
		)
	)
	(bus
		(pts
			(xy 35.56 182.88) (xy 35.56 184.15)
		)
		(stroke
			(width 0)
			(type default)
		)
	)
	(wire
		(pts
			(xy 114.3 120.65) (xy 111.125 120.65)
		)
		(stroke
			(width 0)
			(type default)
		)
	)
	(wire
		(pts
			(xy 106.68 118.11) (xy 106.68 121.92)
		)
		(stroke
			(width 0)
			(type default)
		)
	)
	(wire
		(pts
			(xy 83.82 264.16) (xy 118.11 264.16)
		)
		(stroke
			(width 0)
			(type default)
		)
	)
	(wire
		(pts
			(xy 109.22 228.6) (xy 120.65 228.6)
		)
		(stroke
			(width 0)
			(type default)
		)
	)
	(wire
		(pts
			(xy 204.47 223.52) (xy 204.47 236.22)
		)
		(stroke
			(width 0)
			(type default)
		)
	)
	(wire
		(pts
			(xy 177.8 266.7) (xy 177.8 269.24)
		)
		(stroke
			(width 0)
			(type default)
		)
	)
	(wire
		(pts
			(xy 172.72 130.81) (xy 172.72 133.35)
		)
		(stroke
			(width 0)
			(type default)
		)
	)
	(wire
		(pts
			(xy 313.69 54.61) (xy 313.69 55.88)
		)
		(stroke
			(width 0)
			(type default)
		)
	)
	(wire
		(pts
			(xy 172.72 102.87) (xy 172.72 104.14)
		)
		(stroke
			(width 0)
			(type default)
		)
	)
	(wire
		(pts
			(xy 36.83 251.46) (xy 53.34 251.46)
		)
		(stroke
			(width 0)
			(type default)
		)
	)
	(wire
		(pts
			(xy 195.58 223.52) (xy 168.91 223.52)
		)
		(stroke
			(width 0)
			(type default)
		)
	)
	(wire
		(pts
			(xy 179.07 116.84) (xy 179.07 118.11)
		)
		(stroke
			(width 0)
			(type default)
		)
	)
	(bus
		(pts
			(xy 35.56 228.6) (xy 35.56 229.87)
		)
		(stroke
			(width 0)
			(type default)
		)
	)
	(wire
		(pts
			(xy 137.16 190.5) (xy 144.78 190.5)
		)
		(stroke
			(width 0)
			(type default)
		)
	)
	(wire
		(pts
			(xy 36.83 195.58) (xy 53.34 195.58)
		)
		(stroke
			(width 0)
			(type default)
		)
	)
	(wire
		(pts
			(xy 346.71 71.12) (xy 346.71 83.82)
		)
		(stroke
			(width 0)
			(type default)
		)
	)
	(wire
		(pts
			(xy 152.4 254) (xy 152.4 256.54)
		)
		(stroke
			(width 0)
			(type default)
		)
	)
	(wire
		(pts
			(xy 111.125 120.65) (xy 111.125 107.95)
		)
		(stroke
			(width 0)
			(type default)
		)
	)
	(wire
		(pts
			(xy 152.4 228.6) (xy 152.4 236.22)
		)
		(stroke
			(width 0)
			(type default)
		)
	)
	(wire
		(pts
			(xy 113.665 107.95) (xy 161.29 107.95)
		)
		(stroke
			(width 0)
			(type default)
		)
	)
	(wire
		(pts
			(xy 224.79 190.5) (xy 247.65 190.5)
		)
		(stroke
			(width 0)
			(type default)
		)
	)
	(bus
		(pts
			(xy 62.23 80.01) (xy 60.96 80.01)
		)
		(stroke
			(width 0)
			(type default)
		)
	)
	(wire
		(pts
			(xy 172.72 116.84) (xy 172.72 118.11)
		)
		(stroke
			(width 0)
			(type default)
		)
	)
	(wire
		(pts
			(xy 90.17 135.89) (xy 114.3 135.89)
		)
		(stroke
			(width 0)
			(type default)
		)
	)
	(wire
		(pts
			(xy 36.83 241.3) (xy 53.34 241.3)
		)
		(stroke
			(width 0)
			(type default)
		)
	)
	(wire
		(pts
			(xy 74.93 190.5) (xy 78.74 190.5)
		)
		(stroke
			(width 0)
			(type default)
		)
	)
	(wire
		(pts
			(xy 111.76 140.97) (xy 111.76 143.51)
		)
		(stroke
			(width 0)
			(type default)
		)
	)
	(wire
		(pts
			(xy 313.69 44.45) (xy 303.53 44.45)
		)
		(stroke
			(width 0)
			(type default)
		)
	)
	(wire
		(pts
			(xy 196.85 198.12) (xy 199.39 198.12)
		)
		(stroke
			(width 0)
			(type default)
		)
	)
	(wire
		(pts
			(xy 346.71 34.29) (xy 350.52 34.29)
		)
		(stroke
			(width 0)
			(type default)
		)
	)
	(wire
		(pts
			(xy 83.82 236.22) (xy 101.6 236.22)
		)
		(stroke
			(width 0)
			(type default)
		)
	)
	(wire
		(pts
			(xy 184.15 226.06) (xy 166.37 226.06)
		)
		(stroke
			(width 0)
			(type default)
		)
	)
	(wire
		(pts
			(xy 337.82 21.59) (xy 346.71 21.59)
		)
		(stroke
			(width 0)
			(type default)
		)
	)
	(polyline
		(pts
			(xy 22.86 151.13) (xy 22.86 162.56)
		)
		(stroke
			(width 0)
			(type solid)
		)
	)
	(wire
		(pts
			(xy 125.73 245.11) (xy 125.73 256.54)
		)
		(stroke
			(width 0)
			(type default)
		)
	)
	(wire
		(pts
			(xy 76.2 34.29) (xy 313.69 34.29)
		)
		(stroke
			(width 0)
			(type default)
		)
	)
	(wire
		(pts
			(xy 182.88 76.2) (xy 182.88 83.82)
		)
		(stroke
			(width 0)
			(type default)
		)
	)
	(wire
		(pts
			(xy 115.57 198.12) (xy 115.57 201.93)
		)
		(stroke
			(width 0)
			(type default)
		)
	)
	(wire
		(pts
			(xy 209.55 205.74) (xy 217.17 205.74)
		)
		(stroke
			(width 0)
			(type default)
		)
	)
	(wire
		(pts
			(xy 109.22 190.5) (xy 109.22 228.6)
		)
		(stroke
			(width 0)
			(type default)
		)
	)
	(wire
		(pts
			(xy 144.78 190.5) (xy 144.78 193.04)
		)
		(stroke
			(width 0)
			(type default)
		)
	)
	(wire
		(pts
			(xy 112.395 96.52) (xy 128.905 96.52)
		)
		(stroke
			(width 0)
			(type default)
		)
	)
	(wire
		(pts
			(xy 111.76 140.97) (xy 114.3 140.97)
		)
		(stroke
			(width 0)
			(type default)
		)
	)
	(wire
		(pts
			(xy 168.91 198.12) (xy 176.53 198.12)
		)
		(stroke
			(width 0)
			(type default)
		)
	)
	(wire
		(pts
			(xy 125.73 228.6) (xy 148.59 228.6)
		)
		(stroke
			(width 0)
			(type default)
		)
	)
	(wire
		(pts
			(xy 313.69 177.8) (xy 334.01 177.8)
		)
		(stroke
			(width 0)
			(type default)
		)
	)
	(wire
		(pts
			(xy 130.81 264.16) (xy 153.67 264.16)
		)
		(stroke
			(width 0)
			(type default)
		)
	)
	(wire
		(pts
			(xy 118.11 259.08) (xy 125.73 259.08)
		)
		(stroke
			(width 0)
			(type default)
		)
	)
	(wire
		(pts
			(xy 170.18 143.51) (xy 170.18 147.32)
		)
		(stroke
			(width 0)
			(type default)
		)
	)
	(wire
		(pts
			(xy 342.9 83.82) (xy 346.71 83.82)
		)
		(stroke
			(width 0)
			(type default)
		)
	)
	(wire
		(pts
			(xy 342.9 34.29) (xy 346.71 34.29)
		)
		(stroke
			(width 0)
			(type default)
		)
	)
	(wire
		(pts
			(xy 161.29 83.82) (xy 172.72 83.82)
		)
		(stroke
			(width 0)
			(type default)
		)
	)
	(wire
		(pts
			(xy 90.17 123.19) (xy 104.14 123.19)
		)
		(stroke
			(width 0)
			(type default)
		)
	)
	(wire
		(pts
			(xy 314.96 203.2) (xy 313.69 203.2)
		)
		(stroke
			(width 0)
			(type default)
		)
	)
	(wire
		(pts
			(xy 182.88 83.82) (xy 313.69 83.82)
		)
		(stroke
			(width 0)
			(type default)
		)
	)
	(wire
		(pts
			(xy 74.93 190.5) (xy 74.93 210.82)
		)
		(stroke
			(width 0)
			(type default)
		)
	)
	(wire
		(pts
			(xy 196.85 203.2) (xy 198.12 203.2)
		)
		(stroke
			(width 0)
			(type default)
		)
	)
	(wire
		(pts
			(xy 93.98 83.82) (xy 103.505 83.82)
		)
		(stroke
			(width 0)
			(type default)
		)
	)
	(wire
		(pts
			(xy 332.74 200.66) (xy 346.71 200.66)
		)
		(stroke
			(width 0)
			(type default)
		)
	)
	(wire
		(pts
			(xy 111.76 146.05) (xy 111.76 148.59)
		)
		(stroke
			(width 0)
			(type default)
		)
	)
	(wire
		(pts
			(xy 148.59 238.76) (xy 153.67 238.76)
		)
		(stroke
			(width 0)
			(type default)
		)
	)
	(wire
		(pts
			(xy 64.77 83.82) (xy 90.17 83.82)
		)
		(stroke
			(width 0)
			(type default)
		)
	)
	(polyline
		(pts
			(xy 13.97 158.75) (xy 41.91 158.75)
		)
		(stroke
			(width 0)
			(type solid)
		)
	)
	(wire
		(pts
			(xy 112.395 123.19) (xy 114.3 123.19)
		)
		(stroke
			(width 0)
			(type default)
		)
	)
	(wire
		(pts
			(xy 313.69 190.5) (xy 330.2 190.5)
		)
		(stroke
			(width 0)
			(type default)
		)
	)
	(wire
		(pts
			(xy 63.5 41.91) (xy 63.5 44.45)
		)
		(stroke
			(width 0)
			(type default)
		)
	)
	(wire
		(pts
			(xy 144.78 246.38) (xy 153.67 246.38)
		)
		(stroke
			(width 0)
			(type default)
		)
	)
	(wire
		(pts
			(xy 339.09 91.44) (xy 339.09 96.52)
		)
		(stroke
			(width 0)
			(type default)
		)
	)
	(wire
		(pts
			(xy 112.395 96.52) (xy 112.395 99.06)
		)
		(stroke
			(width 0)
			(type default)
		)
	)
	(wire
		(pts
			(xy 39.37 44.45) (xy 63.5 44.45)
		)
		(stroke
			(width 0)
			(type default)
		)
	)
	(bus
		(pts
			(xy 35.56 184.15) (xy 35.56 194.31)
		)
		(stroke
			(width 0)
			(type default)
		)
	)
	(wire
		(pts
			(xy 172.72 92.71) (xy 172.72 97.79)
		)
		(stroke
			(width 0)
			(type default)
		)
	)
	(wire
		(pts
			(xy 93.98 96.52) (xy 93.98 107.95)
		)
		(stroke
			(width 0)
			(type default)
		)
	)
	(polyline
		(pts
			(xy 247.65 13.97) (xy 247.65 31.75)
		)
		(stroke
			(width 0)
			(type default)
		)
	)
	(wire
		(pts
			(xy 146.05 157.48) (xy 146.05 158.75)
		)
		(stroke
			(width 0)
			(type default)
		)
	)
	(wire
		(pts
			(xy 313.69 99.06) (xy 314.96 99.06)
		)
		(stroke
			(width 0)
			(type default)
		)
	)
	(wire
		(pts
			(xy 152.4 256.54) (xy 153.67 256.54)
		)
		(stroke
			(width 0)
			(type default)
		)
	)
	(wire
		(pts
			(xy 52.07 264.16) (xy 78.74 264.16)
		)
		(stroke
			(width 0)
			(type default)
		)
	)
	(wire
		(pts
			(xy 184.15 251.46) (xy 184.15 256.54)
		)
		(stroke
			(width 0)
			(type default)
		)
	)
	(wire
		(pts
			(xy 303.53 208.28) (xy 303.53 210.82)
		)
		(stroke
			(width 0)
			(type default)
		)
	)
	(wire
		(pts
			(xy 195.58 241.3) (xy 195.58 256.54)
		)
		(stroke
			(width 0)
			(type default)
		)
	)
	(wire
		(pts
			(xy 158.75 198.12) (xy 158.75 208.28)
		)
		(stroke
			(width 0)
			(type default)
		)
	)
	(wire
		(pts
			(xy 313.69 203.2) (xy 313.69 205.74)
		)
		(stroke
			(width 0)
			(type default)
		)
	)
	(bus
		(pts
			(xy 35.56 250.19) (xy 35.56 260.35)
		)
		(stroke
			(width 0)
			(type default)
		)
	)
	(wire
		(pts
			(xy 52.07 256.54) (xy 53.34 256.54)
		)
		(stroke
			(width 0)
			(type default)
		)
	)
	(wire
		(pts
			(xy 53.34 34.29) (xy 63.5 34.29)
		)
		(stroke
			(width 0)
			(type default)
		)
	)
	(bus
		(pts
			(xy 31.75 227.33) (xy 34.29 227.33)
		)
		(stroke
			(width 0)
			(type default)
		)
	)
	(bus
		(pts
			(xy 88.9 130.81) (xy 88.9 132.08)
		)
		(stroke
			(width 0)
			(type default)
		)
	)
	(wire
		(pts
			(xy 36.83 261.62) (xy 53.34 261.62)
		)
		(stroke
			(width 0)
			(type default)
		)
	)
	(wire
		(pts
			(xy 179.07 130.81) (xy 179.07 135.89)
		)
		(stroke
			(width 0)
			(type default)
		)
	)
	(wire
		(pts
			(xy 53.34 190.5) (xy 52.07 190.5)
		)
		(stroke
			(width 0)
			(type default)
		)
	)
	(wire
		(pts
			(xy 38.1 34.29) (xy 48.26 34.29)
		)
		(stroke
			(width 0)
			(type default)
		)
	)
	(wire
		(pts
			(xy 204.47 223.52) (xy 195.58 223.52)
		)
		(stroke
			(width 0)
			(type default)
		)
	)
	(wire
		(pts
			(xy 170.18 152.4) (xy 170.18 153.67)
		)
		(stroke
			(width 0)
			(type default)
		)
	)
	(wire
		(pts
			(xy 151.13 198.12) (xy 151.13 208.28)
		)
		(stroke
			(width 0)
			(type default)
		)
	)
	(wire
		(pts
			(xy 303.53 101.6) (xy 303.53 104.14)
		)
		(stroke
			(width 0)
			(type default)
		)
	)
	(bus
		(pts
			(xy 35.56 182.88) (xy 34.29 181.61)
		)
		(stroke
			(width 0)
			(type default)
		)
	)
	(wire
		(pts
			(xy 346.71 93.98) (xy 346.71 83.82)
		)
		(stroke
			(width 0)
			(type default)
		)
	)
	(wire
		(pts
			(xy 120.65 256.54) (xy 125.73 256.54)
		)
		(stroke
			(width 0)
			(type default)
		)
	)
	(wire
		(pts
			(xy 350.52 190.5) (xy 350.52 203.2)
		)
		(stroke
			(width 0)
			(type default)
		)
	)
	(bus
		(pts
			(xy 35.56 204.47) (xy 35.56 214.63)
		)
		(stroke
			(width 0)
			(type default)
		)
	)
	(wire
		(pts
			(xy 144.78 254) (xy 144.78 256.54)
		)
		(stroke
			(width 0)
			(type default)
		)
	)
	(polyline
		(pts
			(xy 247.65 80.01) (xy 247.65 44.45)
		)
		(stroke
			(width 0)
			(type default)
		)
	)
	(wire
		(pts
			(xy 313.69 104.14) (xy 313.69 105.41)
		)
		(stroke
			(width 0)
			(type default)
		)
	)
	(wire
		(pts
			(xy 350.52 83.82) (xy 350.52 96.52)
		)
		(stroke
			(width 0)
			(type default)
		)
	)
	(wire
		(pts
			(xy 125.73 228.6) (xy 125.73 240.03)
		)
		(stroke
			(width 0)
			(type default)
		)
	)
	(wire
		(pts
			(xy 113.665 107.95) (xy 113.665 125.73)
		)
		(stroke
			(width 0)
			(type default)
		)
	)
	(wire
		(pts
			(xy 313.69 200.66) (xy 314.96 200.66)
		)
		(stroke
			(width 0)
			(type default)
		)
	)
	(bus
		(pts
			(xy 63.5 142.24) (xy 63.5 144.78)
		)
		(stroke
			(width 0)
			(type default)
		)
	)
	(wire
		(pts
			(xy 115.57 208.28) (xy 115.57 207.01)
		)
		(stroke
			(width 0)
			(type default)
		)
	)
	(wire
		(pts
			(xy 198.12 205.74) (xy 209.55 205.74)
		)
		(stroke
			(width 0)
			(type default)
		)
	)
	(wire
		(pts
			(xy 118.11 259.08) (xy 118.11 261.62)
		)
		(stroke
			(width 0)
			(type default)
		)
	)
	(wire
		(pts
			(xy 137.16 198.12) (xy 137.16 208.28)
		)
		(stroke
			(width 0)
			(type default)
		)
	)
	(wire
		(pts
			(xy 209.55 198.12) (xy 209.55 205.74)
		)
		(stroke
			(width 0)
			(type default)
		)
	)
	(wire
		(pts
			(xy 130.81 259.08) (xy 153.67 259.08)
		)
		(stroke
			(width 0)
			(type default)
		)
	)
	(polyline
		(pts
			(xy 13.97 151.13) (xy 41.91 151.13)
		)
		(stroke
			(width 0)
			(type solid)
		)
	)
	(wire
		(pts
			(xy 350.52 34.29) (xy 392.43 34.29)
		)
		(stroke
			(width 0)
			(type default)
		)
	)
	(wire
		(pts
			(xy 38.1 54.61) (xy 39.37 54.61)
		)
		(stroke
			(width 0)
			(type default)
		)
	)
	(wire
		(pts
			(xy 114.3 125.73) (xy 113.665 125.73)
		)
		(stroke
			(width 0)
			(type default)
		)
	)
	(wire
		(pts
			(xy 224.79 190.5) (xy 224.79 193.04)
		)
		(stroke
			(width 0)
			(type default)
		)
	)
	(wire
		(pts
			(xy 93.98 83.82) (xy 93.98 91.44)
		)
		(stroke
			(width 0)
			(type default)
		)
	)
	(wire
		(pts
			(xy 160.02 146.05) (xy 160.02 147.32)
		)
		(stroke
			(width 0)
			(type default)
		)
	)
	(bus
		(pts
			(xy 35.56 240.03) (xy 35.56 250.19)
		)
		(stroke
			(width 0)
			(type default)
		)
	)
	(wire
		(pts
			(xy 52.07 190.5) (xy 52.07 210.82)
		)
		(stroke
			(width 0)
			(type default)
		)
	)
	(wire
		(pts
			(xy 151.13 190.5) (xy 151.13 193.04)
		)
		(stroke
			(width 0)
			(type default)
		)
	)
	(wire
		(pts
			(xy 198.12 203.2) (xy 198.12 205.74)
		)
		(stroke
			(width 0)
			(type default)
		)
	)
	(wire
		(pts
			(xy 172.72 133.35) (xy 144.78 133.35)
		)
		(stroke
			(width 0)
			(type default)
		)
	)
	(wire
		(pts
			(xy 392.43 33.02) (xy 392.43 34.29)
		)
		(stroke
			(width 0)
			(type default)
		)
	)
	(wire
		(pts
			(xy 332.74 96.52) (xy 339.09 96.52)
		)
		(stroke
			(width 0)
			(type default)
		)
	)
	(wire
		(pts
			(xy 111.76 156.21) (xy 111.76 153.67)
		)
		(stroke
			(width 0)
			(type default)
		)
	)
	(wire
		(pts
			(xy 139.065 91.44) (xy 139.065 96.52)
		)
		(stroke
			(width 0)
			(type default)
		)
	)
	(wire
		(pts
			(xy 303.53 210.82) (xy 313.69 210.82)
		)
		(stroke
			(width 0)
			(type default)
		)
	)
	(wire
		(pts
			(xy 175.26 266.7) (xy 177.8 266.7)
		)
		(stroke
			(width 0)
			(type default)
		)
	)
	(wire
		(pts
			(xy 181.61 140.97) (xy 181.61 147.32)
		)
		(stroke
			(width 0)
			(type default)
		)
	)
	(wire
		(pts
			(xy 76.2 34.29) (xy 76.2 38.1)
		)
		(stroke
			(width 0)
			(type default)
		)
	)
	(wire
		(pts
			(xy 332.74 44.45) (xy 346.71 44.45)
		)
		(stroke
			(width 0)
			(type default)
		)
	)
	(wire
		(pts
			(xy 224.79 205.74) (xy 224.79 207.01)
		)
		(stroke
			(width 0)
			(type default)
		)
	)
	(wire
		(pts
			(xy 104.14 128.27) (xy 106.68 128.27)
		)
		(stroke
			(width 0)
			(type default)
		)
	)
	(wire
		(pts
			(xy 144.78 256.54) (xy 152.4 256.54)
		)
		(stroke
			(width 0)
			(type default)
		)
	)
	(wire
		(pts
			(xy 118.11 256.54) (xy 120.65 256.54)
		)
		(stroke
			(width 0)
			(type default)
		)
	)
	(wire
		(pts
			(xy 313.69 21.59) (xy 332.74 21.59)
		)
		(stroke
			(width 0)
			(type default)
		)
	)
	(wire
		(pts
			(xy 128.905 78.74) (xy 128.905 83.82)
		)
		(stroke
			(width 0)
			(type default)
		)
	)
	(wire
		(pts
			(xy 83.82 190.5) (xy 109.22 190.5)
		)
		(stroke
			(width 0)
			(type default)
		)
	)
	(wire
		(pts
			(xy 39.37 44.45) (xy 39.37 54.61)
		)
		(stroke
			(width 0)
			(type default)
		)
	)
	(polyline
		(pts
			(xy 13.97 147.32) (xy 13.97 162.56)
		)
		(stroke
			(width 0)
			(type solid)
		)
	)
	(wire
		(pts
			(xy 112.395 91.44) (xy 112.395 96.52)
		)
		(stroke
			(width 0)
			(type default)
		)
	)
	(wire
		(pts
			(xy 217.17 190.5) (xy 217.17 193.04)
		)
		(stroke
			(width 0)
			(type default)
		)
	)
	(wire
		(pts
			(xy 184.15 256.54) (xy 195.58 256.54)
		)
		(stroke
			(width 0)
			(type default)
		)
	)
	(wire
		(pts
			(xy 120.65 228.6) (xy 125.73 228.6)
		)
		(stroke
			(width 0)
			(type default)
		)
	)
	(wire
		(pts
			(xy 177.8 269.24) (xy 175.26 269.24)
		)
		(stroke
			(width 0)
			(type default)
		)
	)
	(wire
		(pts
			(xy 204.47 241.3) (xy 204.47 247.65)
		)
		(stroke
			(width 0)
			(type default)
		)
	)
	(wire
		(pts
			(xy 350.52 34.29) (xy 350.52 46.99)
		)
		(stroke
			(width 0)
			(type default)
		)
	)
	(wire
		(pts
			(xy 224.79 198.12) (xy 224.79 205.74)
		)
		(stroke
			(width 0)
			(type default)
		)
	)
	(wire
		(pts
			(xy 195.58 223.52) (xy 195.58 236.22)
		)
		(stroke
			(width 0)
			(type default)
		)
	)
	(wire
		(pts
			(xy 177.8 269.24) (xy 184.15 269.24)
		)
		(stroke
			(width 0)
			(type default)
		)
	)
	(wire
		(pts
			(xy 161.29 96.52) (xy 161.29 100.33)
		)
		(stroke
			(width 0)
			(type default)
		)
	)
	(wire
		(pts
			(xy 198.12 193.04) (xy 198.12 190.5)
		)
		(stroke
			(width 0)
			(type default)
		)
	)
	(wire
		(pts
			(xy 313.69 49.53) (xy 313.69 54.61)
		)
		(stroke
			(width 0)
			(type default)
		)
	)
	(wire
		(pts
			(xy 346.71 190.5) (xy 350.52 190.5)
		)
		(stroke
			(width 0)
			(type default)
		)
	)
	(wire
		(pts
			(xy 313.69 177.8) (xy 313.69 190.5)
		)
		(stroke
			(width 0)
			(type default)
		)
	)
	(wire
		(pts
			(xy 152.4 251.46) (xy 152.4 254)
		)
		(stroke
			(width 0)
			(type default)
		)
	)
	(wire
		(pts
			(xy 158.75 190.5) (xy 158.75 193.04)
		)
		(stroke
			(width 0)
			(type default)
		)
	)
	(wire
		(pts
			(xy 74.93 236.22) (xy 74.93 256.54)
		)
		(stroke
			(width 0)
			(type default)
		)
	)
	(wire
		(pts
			(xy 104.14 123.19) (xy 104.14 128.27)
		)
		(stroke
			(width 0)
			(type default)
		)
	)
	(wire
		(pts
			(xy 172.72 83.82) (xy 172.72 87.63)
		)
		(stroke
			(width 0)
			(type default)
		)
	)
	(wire
		(pts
			(xy 350.52 101.6) (xy 350.52 105.41)
		)
		(stroke
			(width 0)
			(type default)
		)
	)
	(wire
		(pts
			(xy 151.13 148.59) (xy 151.13 153.67)
		)
		(stroke
			(width 0)
			(type default)
		)
	)
	(wire
		(pts
			(xy 346.71 177.8) (xy 346.71 190.5)
		)
		(stroke
			(width 0)
			(type default)
		)
	)
	(wire
		(pts
			(xy 314.96 46.99) (xy 313.69 46.99)
		)
		(stroke
			(width 0)
			(type default)
		)
	)
	(wire
		(pts
			(xy 161.29 83.82) (xy 161.29 96.52)
		)
		(stroke
			(width 0)
			(type default)
		)
	)
	(wire
		(pts
			(xy 147.955 83.82) (xy 161.29 83.82)
		)
		(stroke
			(width 0)
			(type default)
		)
	)
	(wire
		(pts
			(xy 90.17 83.82) (xy 93.98 83.82)
		)
		(stroke
			(width 0)
			(type default)
		)
	)
	(wire
		(pts
			(xy 152.4 236.22) (xy 153.67 236.22)
		)
		(stroke
			(width 0)
			(type default)
		)
	)
	(wire
		(pts
			(xy 111.76 156.21) (xy 111.76 158.75)
		)
		(stroke
			(width 0)
			(type default)
		)
	)
	(wire
		(pts
			(xy 144.78 135.89) (xy 179.07 135.89)
		)
		(stroke
			(width 0)
			(type default)
		)
	)
	(wire
		(pts
			(xy 71.12 236.22) (xy 74.93 236.22)
		)
		(stroke
			(width 0)
			(type default)
		)
	)
	(wire
		(pts
			(xy 313.69 205.74) (xy 314.96 205.74)
		)
		(stroke
			(width 0)
			(type default)
		)
	)
	(wire
		(pts
			(xy 179.07 123.19) (xy 179.07 125.73)
		)
		(stroke
			(width 0)
			(type default)
		)
	)
	(bus
		(pts
			(xy 88.9 132.08) (xy 88.9 134.62)
		)
		(stroke
			(width 0)
			(type default)
		)
	)
	(wire
		(pts
			(xy 392.43 83.82) (xy 392.43 190.5)
		)
		(stroke
			(width 0)
			(type default)
		)
	)
	(bus
		(pts
			(xy 63.5 82.55) (xy 63.5 142.24)
		)
		(stroke
			(width 0)
			(type default)
		)
	)
	(wire
		(pts
			(xy 148.59 228.6) (xy 152.4 228.6)
		)
		(stroke
			(width 0)
			(type default)
		)
	)
	(wire
		(pts
			(xy 90.17 133.35) (xy 114.3 133.35)
		)
		(stroke
			(width 0)
			(type default)
		)
	)
	(wire
		(pts
			(xy 142.24 243.84) (xy 153.67 243.84)
		)
		(stroke
			(width 0)
			(type default)
		)
	)
	(wire
		(pts
			(xy 184.15 265.43) (xy 184.15 269.24)
		)
		(stroke
			(width 0)
			(type default)
		)
	)
	(wire
		(pts
			(xy 158.75 190.5) (xy 166.37 190.5)
		)
		(stroke
			(width 0)
			(type default)
		)
	)
	(wire
		(pts
			(xy 182.88 83.82) (xy 182.88 87.63)
		)
		(stroke
			(width 0)
			(type default)
		)
	)
	(wire
		(pts
			(xy 144.78 154.94) (xy 146.05 154.94)
		)
		(stroke
			(width 0)
			(type default)
		)
	)
	(wire
		(pts
			(xy 146.05 154.94) (xy 146.05 157.48)
		)
		(stroke
			(width 0)
			(type default)
		)
	)
	(wire
		(pts
			(xy 39.37 54.61) (xy 76.2 54.61)
		)
		(stroke
			(width 0)
			(type default)
		)
	)
	(wire
		(pts
			(xy 196.85 190.5) (xy 198.12 190.5)
		)
		(stroke
			(width 0)
			(type default)
		)
	)
	(wire
		(pts
			(xy 342.9 190.5) (xy 346.71 190.5)
		)
		(stroke
			(width 0)
			(type default)
		)
	)
	(bus
		(pts
			(xy 35.56 229.87) (xy 35.56 240.03)
		)
		(stroke
			(width 0)
			(type default)
		)
	)
	(wire
		(pts
			(xy 313.69 93.98) (xy 314.96 93.98)
		)
		(stroke
			(width 0)
			(type default)
		)
	)
	(wire
		(pts
			(xy 198.12 190.5) (xy 209.55 190.5)
		)
		(stroke
			(width 0)
			(type default)
		)
	)
	(wire
		(pts
			(xy 313.69 200.66) (xy 303.53 200.66)
		)
		(stroke
			(width 0)
			(type default)
		)
	)
	(wire
		(pts
			(xy 130.81 261.62) (xy 153.67 261.62)
		)
		(stroke
			(width 0)
			(type default)
		)
	)
	(polyline
		(pts
			(xy 41.91 162.56) (xy 13.97 162.56)
		)
		(stroke
			(width 0)
			(type solid)
		)
	)
	(wire
		(pts
			(xy 332.74 93.98) (xy 346.71 93.98)
		)
		(stroke
			(width 0)
			(type default)
		)
	)
	(wire
		(pts
			(xy 139.065 96.52) (xy 142.875 96.52)
		)
		(stroke
			(width 0)
			(type default)
		)
	)
	(wire
		(pts
			(xy 118.11 261.62) (xy 125.73 261.62)
		)
		(stroke
			(width 0)
			(type default)
		)
	)
	(wire
		(pts
			(xy 303.53 52.07) (xy 303.53 54.61)
		)
		(stroke
			(width 0)
			(type default)
		)
	)
	(wire
		(pts
			(xy 144.78 157.48) (xy 146.05 157.48)
		)
		(stroke
			(width 0)
			(type default)
		)
	)
	(wire
		(pts
			(xy 313.69 93.98) (xy 303.53 93.98)
		)
		(stroke
			(width 0)
			(type default)
		)
	)
	(wire
		(pts
			(xy 184.15 226.06) (xy 184.15 246.38)
		)
		(stroke
			(width 0)
			(type default)
		)
	)
	(wire
		(pts
			(xy 64.77 146.05) (xy 111.76 146.05)
		)
		(stroke
			(width 0)
			(type default)
		)
	)
	(polyline
		(pts
			(xy 247.65 86.36) (xy 247.65 165.1)
		)
		(stroke
			(width 0)
			(type default)
		)
	)
	(wire
		(pts
			(xy 118.11 264.16) (xy 125.73 264.16)
		)
		(stroke
			(width 0)
			(type default)
		)
	)
	(wire
		(pts
			(xy 90.17 118.11) (xy 106.68 118.11)
		)
		(stroke
			(width 0)
			(type default)
		)
	)
	(wire
		(pts
			(xy 144.78 148.59) (xy 151.13 148.59)
		)
		(stroke
			(width 0)
			(type default)
		)
	)
	(polyline
		(pts
			(xy 13.97 165.1) (xy 247.65 165.1)
		)
		(stroke
			(width 0)
			(type default)
		)
	)
	(wire
		(pts
			(xy 313.69 49.53) (xy 314.96 49.53)
		)
		(stroke
			(width 0)
			(type default)
		)
	)
	(wire
		(pts
			(xy 52.07 210.82) (xy 53.34 210.82)
		)
		(stroke
			(width 0)
			(type default)
		)
	)
	(wire
		(pts
			(xy 166.37 226.06) (xy 166.37 190.5)
		)
		(stroke
			(width 0)
			(type default)
		)
	)
	(wire
		(pts
			(xy 332.74 203.2) (xy 339.09 203.2)
		)
		(stroke
			(width 0)
			(type default)
		)
	)
	(wire
		(pts
			(xy 83.82 219.71) (xy 101.6 219.71)
		)
		(stroke
			(width 0)
			(type default)
		)
	)
	(wire
		(pts
			(xy 112.395 104.14) (xy 112.395 123.19)
		)
		(stroke
			(width 0)
			(type default)
		)
	)
	(wire
		(pts
			(xy 313.69 99.06) (xy 313.69 104.14)
		)
		(stroke
			(width 0)
			(type default)
		)
	)
	(wire
		(pts
			(xy 209.55 190.5) (xy 217.17 190.5)
		)
		(stroke
			(width 0)
			(type default)
		)
	)
	(wire
		(pts
			(xy 53.34 236.22) (xy 52.07 236.22)
		)
		(stroke
			(width 0)
			(type default)
		)
	)
	(wire
		(pts
			(xy 303.53 93.98) (xy 303.53 96.52)
		)
		(stroke
			(width 0)
			(type default)
		)
	)
	(wire
		(pts
			(xy 313.69 44.45) (xy 314.96 44.45)
		)
		(stroke
			(width 0)
			(type default)
		)
	)
	(wire
		(pts
			(xy 350.52 83.82) (xy 392.43 83.82)
		)
		(stroke
			(width 0)
			(type default)
		)
	)
	(wire
		(pts
			(xy 115.57 190.5) (xy 137.16 190.5)
		)
		(stroke
			(width 0)
			(type default)
		)
	)
	(wire
		(pts
			(xy 160.02 152.4) (xy 160.02 153.67)
		)
		(stroke
			(width 0)
			(type default)
		)
	)
	(wire
		(pts
			(xy 303.53 54.61) (xy 313.69 54.61)
		)
		(stroke
			(width 0)
			(type default)
		)
	)
	(wire
		(pts
			(xy 36.83 185.42) (xy 53.34 185.42)
		)
		(stroke
			(width 0)
			(type default)
		)
	)
	(wire
		(pts
			(xy 196.85 193.04) (xy 198.12 193.04)
		)
		(stroke
			(width 0)
			(type default)
		)
	)
	(wire
		(pts
			(xy 120.65 228.6) (xy 120.65 240.03)
		)
		(stroke
			(width 0)
			(type default)
		)
	)
	(wire
		(pts
			(xy 303.53 44.45) (xy 303.53 46.99)
		)
		(stroke
			(width 0)
			(type default)
		)
	)
	(wire
		(pts
			(xy 182.88 92.71) (xy 182.88 93.98)
		)
		(stroke
			(width 0)
			(type default)
		)
	)
	(wire
		(pts
			(xy 125.73 256.54) (xy 142.24 256.54)
		)
		(stroke
			(width 0)
			(type default)
		)
	)
	(wire
		(pts
			(xy 144.78 190.5) (xy 151.13 190.5)
		)
		(stroke
			(width 0)
			(type default)
		)
	)
	(wire
		(pts
			(xy 175.26 256.54) (xy 184.15 256.54)
		)
		(stroke
			(width 0)
			(type default)
		)
	)
	(wire
		(pts
			(xy 313.69 83.82) (xy 313.69 93.98)
		)
		(stroke
			(width 0)
			(type default)
		)
	)
	(wire
		(pts
			(xy 346.71 21.59) (xy 346.71 34.29)
		)
		(stroke
			(width 0)
			(type default)
		)
	)
	(wire
		(pts
			(xy 313.69 34.29) (xy 330.2 34.29)
		)
		(stroke
			(width 0)
			(type default)
		)
	)
	(bus
		(pts
			(xy 88.9 118.11) (xy 87.63 118.11)
		)
		(stroke
			(width 0)
			(type default)
		)
	)
	(wire
		(pts
			(xy 111.76 146.05) (xy 114.3 146.05)
		)
		(stroke
			(width 0)
			(type default)
		)
	)
	(wire
		(pts
			(xy 144.78 143.51) (xy 170.18 143.51)
		)
		(stroke
			(width 0)
			(type default)
		)
	)
	(wire
		(pts
			(xy 39.37 36.83) (xy 39.37 39.37)
		)
		(stroke
			(width 0)
			(type default)
		)
	)
	(wire
		(pts
			(xy 313.69 46.99) (xy 313.69 49.53)
		)
		(stroke
			(width 0)
			(type default)
		)
	)
	(wire
		(pts
			(xy 247.65 189.23) (xy 248.92 189.23)
		)
		(stroke
			(width 0)
			(type default)
		)
	)
	(bus
		(pts
			(xy 63.5 81.28) (xy 63.5 82.55)
		)
		(stroke
			(width 0)
			(type default)
		)
	)
	(wire
		(pts
			(xy 142.24 243.84) (xy 142.24 248.92)
		)
		(stroke
			(width 0)
			(type default)
		)
	)
	(wire
		(pts
			(xy 106.68 128.27) (xy 114.3 128.27)
		)
		(stroke
			(width 0)
			(type default)
		)
	)
	(wire
		(pts
			(xy 153.67 251.46) (xy 152.4 251.46)
		)
		(stroke
			(width 0)
			(type default)
		)
	)
	(wire
		(pts
			(xy 115.57 190.5) (xy 115.57 193.04)
		)
		(stroke
			(width 0)
			(type default)
		)
	)
	(bus
		(pts
			(xy 63.5 81.28) (xy 62.23 80.01)
		)
		(stroke
			(width 0)
			(type default)
		)
	)
	(wire
		(pts
			(xy 128.905 83.82) (xy 128.905 86.36)
		)
		(stroke
			(width 0)
			(type default)
		)
	)
	(wire
		(pts
			(xy 339.09 71.12) (xy 346.71 71.12)
		)
		(stroke
			(width 0)
			(type default)
		)
	)
	(wire
		(pts
			(xy 111.76 143.51) (xy 114.3 143.51)
		)
		(stroke
			(width 0)
			(type default)
		)
	)
	(wire
		(pts
			(xy 109.22 190.5) (xy 115.57 190.5)
		)
		(stroke
			(width 0)
			(type default)
		)
	)
	(bus
		(pts
			(xy 88.9 123.19) (xy 87.63 123.19)
		)
		(stroke
			(width 0)
			(type default)
		)
	)
	(wire
		(pts
			(xy 209.55 190.5) (xy 209.55 193.04)
		)
		(stroke
			(width 0)
			(type default)
		)
	)
	(polyline
		(pts
			(xy 247.65 284.48) (xy 247.65 193.04)
		)
		(stroke
			(width 0)
			(type default)
		)
	)
	(wire
		(pts
			(xy 156.845 96.52) (xy 161.29 96.52)
		)
		(stroke
			(width 0)
			(type default)
		)
	)
	(wire
		(pts
			(xy 313.69 71.12) (xy 313.69 83.82)
		)
		(stroke
			(width 0)
			(type default)
		)
	)
	(wire
		(pts
			(xy 172.72 83.82) (xy 182.88 83.82)
		)
		(stroke
			(width 0)
			(type default)
		)
	)
	(wire
		(pts
			(xy 313.69 190.5) (xy 313.69 200.66)
		)
		(stroke
			(width 0)
			(type default)
		)
	)
	(wire
		(pts
			(xy 350.52 52.07) (xy 350.52 55.88)
		)
		(stroke
			(width 0)
			(type default)
		)
	)
	(wire
		(pts
			(xy 168.91 198.12) (xy 168.91 223.52)
		)
		(stroke
			(width 0)
			(type default)
		)
	)
	(wire
		(pts
			(xy 36.83 215.9) (xy 53.34 215.9)
		)
		(stroke
			(width 0)
			(type default)
		)
	)
	(wire
		(pts
			(xy 90.17 83.82) (xy 90.17 91.44)
		)
		(stroke
			(width 0)
			(type default)
		)
	)
	(bus
		(pts
			(xy 31.75 181.61) (xy 34.29 181.61)
		)
		(stroke
			(width 0)
			(type default)
		)
	)
	(polyline
		(pts
			(xy 247.65 187.96) (xy 247.65 165.1)
		)
		(stroke
			(width 0)
			(type default)
		)
	)
	(wire
		(pts
			(xy 332.74 46.99) (xy 339.09 46.99)
		)
		(stroke
			(width 0)
			(type default)
		)
	)
	(bus
		(pts
			(xy 35.56 228.6) (xy 34.29 227.33)
		)
		(stroke
			(width 0)
			(type default)
		)
	)
	(wire
		(pts
			(xy 175.26 205.74) (xy 175.26 207.01)
		)
		(stroke
			(width 0)
			(type default)
		)
	)
	(wire
		(pts
			(xy 144.78 146.05) (xy 160.02 146.05)
		)
		(stroke
			(width 0)
			(type default)
		)
	)
	(wire
		(pts
			(xy 313.69 83.82) (xy 330.2 83.82)
		)
		(stroke
			(width 0)
			(type default)
		)
	)
	(wire
		(pts
			(xy 128.905 91.44) (xy 128.905 96.52)
		)
		(stroke
			(width 0)
			(type default)
		)
	)
	(wire
		(pts
			(xy 63.5 34.29) (xy 63.5 36.83)
		)
		(stroke
			(width 0)
			(type default)
		)
	)
	(wire
		(pts
			(xy 52.07 219.71) (xy 78.74 219.71)
		)
		(stroke
			(width 0)
			(type default)
		)
	)
	(wire
		(pts
			(xy 64.77 143.51) (xy 111.76 143.51)
		)
		(stroke
			(width 0)
			(type default)
		)
	)
	(wire
		(pts
			(xy 38.1 36.83) (xy 39.37 36.83)
		)
		(stroke
			(width 0)
			(type default)
		)
	)
	(polyline
		(pts
			(xy 13.97 154.94) (xy 41.91 154.94)
		)
		(stroke
			(width 0)
			(type solid)
		)
	)
	(wire
		(pts
			(xy 204.47 260.35) (xy 204.47 262.89)
		)
		(stroke
			(width 0)
			(type default)
		)
	)
	(wire
		(pts
			(xy 39.37 39.37) (xy 38.1 39.37)
		)
		(stroke
			(width 0)
			(type default)
		)
	)
	(wire
		(pts
			(xy 144.78 198.12) (xy 144.78 208.28)
		)
		(stroke
			(width 0)
			(type default)
		)
	)
	(bus
		(pts
			(xy 87.63 129.54) (xy 88.9 130.81)
		)
		(stroke
			(width 0)
			(type default)
		)
	)
	(polyline
		(pts
			(xy 247.65 44.45) (xy 247.65 35.56)
		)
		(stroke
			(width 0)
			(type default)
		)
	)
	(wire
		(pts
			(xy 71.12 256.54) (xy 74.93 256.54)
		)
		(stroke
			(width 0)
			(type default)
		)
	)
	(wire
		(pts
			(xy 71.12 190.5) (xy 74.93 190.5)
		)
		(stroke
			(width 0)
			(type default)
		)
	)
	(polyline
		(pts
			(xy 12.7 67.31) (xy 247.65 67.31)
		)
		(stroke
			(width 0)
			(type default)
		)
	)
	(wire
		(pts
			(xy 339.09 198.12) (xy 339.09 203.2)
		)
		(stroke
			(width 0)
			(type default)
		)
	)
	(wire
		(pts
			(xy 63.5 34.29) (xy 76.2 34.29)
		)
		(stroke
			(width 0)
			(type default)
		)
	)
	(wire
		(pts
			(xy 39.37 39.37) (xy 39.37 44.45)
		)
		(stroke
			(width 0)
			(type default)
		)
	)
	(wire
		(pts
			(xy 36.83 231.14) (xy 53.34 231.14)
		)
		(stroke
			(width 0)
			(type default)
		)
	)
	(wire
		(pts
			(xy 339.09 177.8) (xy 346.71 177.8)
		)
		(stroke
			(width 0)
			(type default)
		)
	)
	(wire
		(pts
			(xy 247.65 190.5) (xy 313.69 190.5)
		)
		(stroke
			(width 0)
			(type default)
		)
	)
	(wire
		(pts
			(xy 350.52 208.28) (xy 350.52 212.09)
		)
		(stroke
			(width 0)
			(type default)
		)
	)
	(wire
		(pts
			(xy 152.4 254) (xy 153.67 254)
		)
		(stroke
			(width 0)
			(type default)
		)
	)
	(wire
		(pts
			(xy 247.65 189.23) (xy 247.65 190.5)
		)
		(stroke
			(width 0)
			(type default)
		)
	)
	(polyline
		(pts
			(xy 13.97 147.32) (xy 41.91 147.32)
		)
		(stroke
			(width 0)
			(type solid)
		)
	)
	(wire
		(pts
			(xy 128.905 83.82) (xy 135.255 83.82)
		)
		(stroke
			(width 0)
			(type default)
		)
	)
	(wire
		(pts
			(xy 106.68 127) (xy 106.68 128.27)
		)
		(stroke
			(width 0)
			(type default)
		)
	)
	(wire
		(pts
			(xy 151.13 190.5) (xy 158.75 190.5)
		)
		(stroke
			(width 0)
			(type default)
		)
	)
	(wire
		(pts
			(xy 346.71 200.66) (xy 346.71 190.5)
		)
		(stroke
			(width 0)
			(type default)
		)
	)
	(wire
		(pts
			(xy 71.12 210.82) (xy 74.93 210.82)
		)
		(stroke
			(width 0)
			(type default)
		)
	)
	(wire
		(pts
			(xy 148.59 228.6) (xy 148.59 231.14)
		)
		(stroke
			(width 0)
			(type default)
		)
	)
	(wire
		(pts
			(xy 350.52 190.5) (xy 392.43 190.5)
		)
		(stroke
			(width 0)
			(type default)
		)
	)
	(wire
		(pts
			(xy 161.29 105.41) (xy 161.29 107.95)
		)
		(stroke
			(width 0)
			(type default)
		)
	)
	(wire
		(pts
			(xy 118.11 261.62) (xy 118.11 264.16)
		)
		(stroke
			(width 0)
			(type default)
		)
	)
	(wire
		(pts
			(xy 313.69 205.74) (xy 313.69 210.82)
		)
		(stroke
			(width 0)
			(type default)
		)
	)
	(wire
		(pts
			(xy 217.17 198.12) (xy 217.17 205.74)
		)
		(stroke
			(width 0)
			(type default)
		)
	)
	(wire
		(pts
			(xy 313.69 34.29) (xy 313.69 44.45)
		)
		(stroke
			(width 0)
			(type default)
		)
	)
	(wire
		(pts
			(xy 142.24 254) (xy 142.24 256.54)
		)
		(stroke
			(width 0)
			(type default)
		)
	)
	(bus
		(pts
			(xy 35.56 194.31) (xy 35.56 204.47)
		)
		(stroke
			(width 0)
			(type default)
		)
	)
	(wire
		(pts
			(xy 76.2 43.18) (xy 76.2 54.61)
		)
		(stroke
			(width 0)
			(type default)
		)
	)
	(wire
		(pts
			(xy 392.43 34.29) (xy 392.43 83.82)
		)
		(stroke
			(width 0)
			(type default)
		)
	)
	(wire
		(pts
			(xy 346.71 83.82) (xy 350.52 83.82)
		)
		(stroke
			(width 0)
			(type default)
		)
	)
	(wire
		(pts
			(xy 144.78 140.97) (xy 181.61 140.97)
		)
		(stroke
			(width 0)
			(type default)
		)
	)
	(wire
		(pts
			(xy 166.37 190.5) (xy 176.53 190.5)
		)
		(stroke
			(width 0)
			(type default)
		)
	)
	(wire
		(pts
			(xy 181.61 152.4) (xy 181.61 153.67)
		)
		(stroke
			(width 0)
			(type default)
		)
	)
	(wire
		(pts
			(xy 148.59 236.22) (xy 148.59 238.76)
		)
		(stroke
			(width 0)
			(type default)
		)
	)
	(wire
		(pts
			(xy 177.8 269.24) (xy 177.8 271.78)
		)
		(stroke
			(width 0)
			(type default)
		)
	)
	(wire
		(pts
			(xy 118.11 259.08) (xy 118.11 256.54)
		)
		(stroke
			(width 0)
			(type default)
		)
	)
	(wire
		(pts
			(xy 313.69 96.52) (xy 313.69 99.06)
		)
		(stroke
			(width 0)
			(type default)
		)
	)
	(wire
		(pts
			(xy 111.76 148.59) (xy 114.3 148.59)
		)
		(stroke
			(width 0)
			(type default)
		)
	)
	(wire
		(pts
			(xy 346.71 44.45) (xy 346.71 34.29)
		)
		(stroke
			(width 0)
			(type default)
		)
	)
	(label "POE_ACTIVE"
		(at 204.47 223.52 180)
		(effects
			(font
				(size 1.27 1.27)
			)
			(justify right bottom)
		)
	)
	(label "USB_DBG_PD.CC1"
		(at 69.85 143.51 0)
		(effects
			(font
				(size 1.27 1.27)
			)
			(justify left bottom)
		)
	)
	(label "PD_VBUS"
		(at 147.32 140.97 0)
		(effects
			(font
				(size 1.27 1.27)
			)
			(justify left bottom)
		)
	)
	(label "PD_VBUS"
		(at 116.205 83.82 0)
		(effects
			(font
				(size 1.27 1.27)
			)
			(justify left bottom)
		)
	)
	(label "POE_GBE.VC2"
		(at 38.1 185.42 0)
		(effects
			(font
				(size 1.27 1.27)
			)
			(justify left bottom)
		)
	)
	(label "AMPS_CTL"
		(at 153.67 259.08 180)
		(effects
			(font
				(size 1.27 1.27)
			)
			(justify right bottom)
		)
	)
	(label "VDD"
		(at 101.6 236.22 180)
		(effects
			(font
				(size 1.27 1.27)
			)
			(justify right bottom)
		)
	)
	(label "VSS"
		(at 97.79 264.16 0)
		(effects
			(font
				(size 1.27 1.27)
			)
			(justify left bottom)
		)
	)
	(label "PDBUS_DISCH"
		(at 144.78 107.95 0)
		(effects
			(font
				(size 1.27 1.27)
			)
			(justify left bottom)
		)
	)
	(label "CLSA"
		(at 144.78 243.84 0)
		(effects
			(font
				(size 1.27 1.27)
			)
			(justify left bottom)
		)
	)
	(label "POE_ETH.VC1"
		(at 36.83 241.3 0)
		(effects
			(font
				(size 1.27 1.27)
			)
			(justify left bottom)
		)
	)
	(label "POE_ETH.VC3"
		(at 36.83 251.46 0)
		(effects
			(font
				(size 1.27 1.27)
			)
			(justify left bottom)
		)
	)
	(label "I2C.SDA"
		(at 91.44 135.89 0)
		(effects
			(font
				(size 1.27 1.27)
			)
			(justify left bottom)
		)
	)
	(label "POE_ETH.VC4"
		(at 36.83 261.62 0)
		(effects
			(font
				(size 1.27 1.27)
			)
			(justify left bottom)
		)
	)
	(label "POE_ETH.VC2"
		(at 36.83 231.14 0)
		(effects
			(font
				(size 1.27 1.27)
			)
			(justify left bottom)
		)
	)
	(label "SUP_MCU.PD_RST"
		(at 91.44 118.11 0)
		(effects
			(font
				(size 1.27 1.27)
			)
			(justify left bottom)
		)
	)
	(label "VREG_2V7"
		(at 147.32 146.05 0)
		(effects
			(font
				(size 1.27 1.27)
			)
			(justify left bottom)
		)
	)
	(label "VDD"
		(at 97.79 190.5 0)
		(effects
			(font
				(size 1.27 1.27)
			)
			(justify left bottom)
		)
	)
	(label "VSS"
		(at 101.6 219.71 180)
		(effects
			(font
				(size 1.27 1.27)
			)
			(justify right bottom)
		)
	)
	(label "DC_IN"
		(at 247.65 34.29 180)
		(effects
			(font
				(size 1.27 1.27)
			)
			(justify right bottom)
		)
	)
	(label "VBUS_DIS"
		(at 100.33 107.95 0)
		(effects
			(font
				(size 1.27 1.27)
			)
			(justify left bottom)
		)
	)
	(label "POE_GBE.VC4"
		(at 38.1 215.9 0)
		(effects
			(font
				(size 1.27 1.27)
			)
			(justify left bottom)
		)
	)
	(label "I2C.SCL"
		(at 91.44 133.35 0)
		(effects
			(font
				(size 1.27 1.27)
			)
			(justify left bottom)
		)
	)
	(label "MPS_DUTY"
		(at 153.67 264.16 180)
		(effects
			(font
				(size 1.27 1.27)
			)
			(justify right bottom)
		)
	)
	(label "POE_GBE.VC3"
		(at 38.1 205.74 0)
		(effects
			(font
				(size 1.27 1.27)
			)
			(justify left bottom)
		)
	)
	(label "PD_PWR_OK2"
		(at 147.32 133.35 0)
		(effects
			(font
				(size 1.27 1.27)
			)
			(justify left bottom)
		)
	)
	(label "USB_DBG_PD.VBUS"
		(at 69.85 83.82 0)
		(effects
			(font
				(size 1.27 1.27)
			)
			(justify left bottom)
		)
	)
	(label "USB_DBG_PD.CC2"
		(at 69.85 146.05 0)
		(effects
			(font
				(size 1.27 1.27)
			)
			(justify left bottom)
		)
	)
	(label "PD_CTRL.RESET"
		(at 91.44 123.19 0)
		(effects
			(font
				(size 1.27 1.27)
			)
			(justify left bottom)
		)
	)
	(label "POE_GBE.VC1"
		(at 38.1 195.58 0)
		(effects
			(font
				(size 1.27 1.27)
			)
			(justify left bottom)
		)
	)
	(label "SINK_EN"
		(at 116.205 96.52 0)
		(effects
			(font
				(size 1.27 1.27)
			)
			(justify left bottom)
		)
	)
	(label "REF"
		(at 153.67 261.62 180)
		(effects
			(font
				(size 1.27 1.27)
			)
			(justify right bottom)
		)
	)
	(label "CLSB"
		(at 144.78 246.38 0)
		(effects
			(font
				(size 1.27 1.27)
			)
			(justify left bottom)
		)
	)
	(label "DEN"
		(at 153.67 238.76 180)
		(effects
			(font
				(size 1.27 1.27)
			)
			(justify right bottom)
		)
	)
	(label "USB_PD_VBUS"
		(at 247.65 83.82 180)
		(effects
			(font
				(size 1.27 1.27)
			)
			(justify right bottom)
		)
	)
	(label "PG"
		(at 179.07 256.54 180)
		(effects
			(font
				(size 1.27 1.27)
			)
			(justify right bottom)
		)
	)
	(label "VREG_1V2"
		(at 147.32 143.51 0)
		(effects
			(font
				(size 1.27 1.27)
			)
			(justify left bottom)
		)
	)
	(label "PD_PWR_OK3"
		(at 147.32 135.89 0)
		(effects
			(font
				(size 1.27 1.27)
			)
			(justify left bottom)
		)
	)
	(global_label "GND"
		(shape input)
		(at 38.1 54.61 180)
		(fields_autoplaced yes)
		(effects
			(font
				(size 1.27 1.27)
			)
			(justify right)
		)
		(property "Intersheetrefs" "${INTERSHEET_REFS}"
			(at 31.8164 54.5306 0)
			(effects
				(font
					(size 1.27 1.27)
				)
				(justify right)
				(hide yes)
			)
		)
	)
	(hierarchical_label "POE_GBE{POE}"
		(shape input)
		(at 31.75 181.61 180)
		(effects
			(font
				(size 1.27 1.27)
			)
			(justify right)
		)
	)
	(hierarchical_label "USB_DBG_PD{USB-C-PD}"
		(shape bidirectional)
		(at 60.96 80.01 180)
		(effects
			(font
				(size 1.27 1.27)
			)
			(justify right)
		)
	)
	(hierarchical_label "PD_CTRL{STUSB4500}"
		(shape bidirectional)
		(at 87.63 123.19 180)
		(effects
			(font
				(size 1.27 1.27)
			)
			(justify right)
		)
	)
	(hierarchical_label "SUP_MCU{SUP-MCU}"
		(shape bidirectional)
		(at 87.63 118.11 180)
		(effects
			(font
				(size 1.27 1.27)
			)
			(justify right)
		)
	)
	(hierarchical_label "POE_DC"
		(shape output)
		(at 248.92 189.23 0)
		(effects
			(font
				(size 1.27 1.27)
			)
			(justify left)
		)
	)
	(hierarchical_label "POE_ETH{POE}"
		(shape input)
		(at 31.75 227.33 180)
		(effects
			(font
				(size 1.27 1.27)
			)
			(justify right)
		)
	)
	(hierarchical_label "I2C{I2C}"
		(shape bidirectional)
		(at 86.36 129.54 180)
		(effects
			(font
				(size 1.27 1.27)
			)
			(justify right)
		)
	)
	(symbol
		(lib_id "antmicroTVSDiodes:CD-MMBL110S")
		(at 53.34 185.42 0)
		(unit 1)
		(exclude_from_sim no)
		(in_bom yes)
		(on_board yes)
		(dnp no)
		(fields_autoplaced yes)
		(property "Reference" "D4"
			(at 62.23 179.07 0)
			(effects
				(font
					(size 1.27 1.27)
				)
			)
		)
		(property "Value" "CD-MMBL110S"
			(at 62.23 181.61 0)
			(effects
				(font
					(size 1.27 1.27)
					(thickness 0.15)
				)
				(hide yes)
			)
		)
		(property "Footprint" "antmicro-footprints:DFN3538"
			(at 85.09 195.58 0)
			(effects
				(font
					(size 1.27 1.27)
					(thickness 0.15)
				)
				(justify left bottom)
				(hide yes)
			)
		)
		(property "Datasheet" "https://www.bourns.com/docs/product-datasheets/CD-MMBL110S.pdf"
			(at 85.09 198.12 0)
			(effects
				(font
					(size 1.27 1.27)
					(thickness 0.15)
				)
				(justify left bottom)
				(hide yes)
			)
		)
		(property "Description" ""
			(at 53.34 185.42 0)
			(effects
				(font
					(size 1.27 1.27)
				)
			)
		)
		(property "MPN" "CD-MMBL110S"
			(at 62.23 181.61 0)
			(effects
				(font
					(size 1.27 1.27)
					(thickness 0.15)
				)
			)
		)
		(property "Manufacturer" "Bourns"
			(at 85.09 203.2 0)
			(effects
				(font
					(size 1.27 1.27)
					(thickness 0.15)
				)
				(justify left bottom)
				(hide yes)
			)
		)
		(property "Author" "Antmicro"
			(at 85.09 205.74 0)
			(effects
				(font
					(size 1.27 1.27)
					(thickness 0.15)
				)
				(justify left bottom)
				(hide yes)
			)
		)
		(property "License" "Apache-2.0"
			(at 85.09 208.28 0)
			(effects
				(font
					(size 1.27 1.27)
					(thickness 0.15)
				)
				(justify left bottom)
				(hide yes)
			)
		)
		(pin "1"
		)
		(pin "2"
		)
		(pin "3"
		)
		(pin "4"
		)
		(instances
			(project "k410t-devboard"
				(path ""
					(reference "D4")
					(unit 1)
				)
			)
		)
	)
	(symbol
		(lib_id "antmicropower:GND")
		(at 224.79 207.01 0)
		(unit 1)
		(exclude_from_sim no)
		(in_bom yes)
		(on_board yes)
		(dnp no)
		(fields_autoplaced yes)
		(property "Reference" "#PWR0108"
			(at 224.79 213.36 0)
			(effects
				(font
					(size 1.27 1.27)
				)
				(hide yes)
			)
		)
		(property "Value" "GND"
			(at 224.79 210.82 0)
			(effects
				(font
					(size 1.27 1.27)
				)
			)
		)
		(property "Footprint" ""
			(at 233.68 214.63 0)
			(effects
				(font
					(size 1.27 1.27)
					(thickness 0.15)
				)
				(justify left bottom)
				(hide yes)
			)
		)
		(property "Datasheet" ""
			(at 233.68 219.71 0)
			(effects
				(font
					(size 1.27 1.27)
					(thickness 0.15)
				)
				(justify left bottom)
				(hide yes)
			)
		)
		(property "Description" ""
			(at 224.79 207.01 0)
			(effects
				(font
					(size 1.27 1.27)
				)
			)
		)
		(property "Author" "Antmicro"
			(at 233.68 214.63 0)
			(effects
				(font
					(size 1.27 1.27)
					(thickness 0.15)
				)
				(justify left bottom)
				(hide yes)
			)
		)
		(property "License" "Apache-2.0"
			(at 233.68 217.17 0)
			(effects
				(font
					(size 1.27 1.27)
					(thickness 0.15)
				)
				(justify left bottom)
				(hide yes)
			)
		)
		(pin "1"
		)
		(instances
			(project "k410t-devboard"
				(path ""
					(reference "#PWR0108")
					(unit 1)
				)
			)
		)
	)
	(symbol
		(lib_id "antmicropower:GND")
		(at 350.52 212.09 0)
		(unit 1)
		(exclude_from_sim no)
		(in_bom yes)
		(on_board yes)
		(dnp no)
		(fields_autoplaced yes)
		(property "Reference" "#PWR0117"
			(at 350.52 218.44 0)
			(effects
				(font
					(size 1.27 1.27)
				)
				(hide yes)
			)
		)
		(property "Value" "GND"
			(at 350.52 215.9 0)
			(effects
				(font
					(size 1.27 1.27)
				)
			)
		)
		(property "Footprint" ""
			(at 359.41 219.71 0)
			(effects
				(font
					(size 1.27 1.27)
					(thickness 0.15)
				)
				(justify left bottom)
				(hide yes)
			)
		)
		(property "Datasheet" ""
			(at 359.41 224.79 0)
			(effects
				(font
					(size 1.27 1.27)
					(thickness 0.15)
				)
				(justify left bottom)
				(hide yes)
			)
		)
		(property "Description" ""
			(at 350.52 212.09 0)
			(effects
				(font
					(size 1.27 1.27)
				)
			)
		)
		(property "Author" "Antmicro"
			(at 359.41 219.71 0)
			(effects
				(font
					(size 1.27 1.27)
					(thickness 0.15)
				)
				(justify left bottom)
				(hide yes)
			)
		)
		(property "License" "Apache-2.0"
			(at 359.41 222.25 0)
			(effects
				(font
					(size 1.27 1.27)
					(thickness 0.15)
				)
				(justify left bottom)
				(hide yes)
			)
		)
		(pin "1"
		)
		(instances
			(project "k410t-devboard"
				(path ""
					(reference "#PWR0117")
					(unit 1)
				)
			)
		)
	)
	(symbol
		(lib_id "antmicroCapacitors0402:C_100n_0402")
		(at 63.5 41.91 90)
		(unit 1)
		(exclude_from_sim no)
		(in_bom yes)
		(on_board yes)
		(dnp no)
		(fields_autoplaced yes)
		(property "Reference" "C190"
			(at 66.04 38.0935 90)
			(effects
				(font
					(size 1.27 1.27)
				)
				(justify right)
			)
		)
		(property "Value" "C_100n_0402"
			(at 73.66 21.59 0)
			(effects
				(font
					(size 1.27 1.27)
					(thickness 0.15)
				)
				(justify left bottom)
				(hide yes)
			)
		)
		(property "Footprint" "antmicro-footprints:C_0402_1005Metric"
			(at 76.2 21.59 0)
			(effects
				(font
					(size 1.27 1.27)
					(thickness 0.15)
				)
				(justify left bottom)
				(hide yes)
			)
		)
		(property "Datasheet" "https://www.murata.com/products/productdetail?partno=GRM155R61H104KE14%23"
			(at 78.74 21.59 0)
			(effects
				(font
					(size 1.27 1.27)
					(thickness 0.15)
				)
				(justify left bottom)
				(hide yes)
			)
		)
		(property "Description" ""
			(at 63.5 41.91 0)
			(effects
				(font
					(size 1.27 1.27)
				)
			)
		)
		(property "Manufacturer" "Murata"
			(at 83.82 21.59 0)
			(effects
				(font
					(size 1.27 1.27)
					(thickness 0.15)
				)
				(justify left bottom)
				(hide yes)
			)
		)
		(property "MPN" "GRM155R61H104KE14D"
			(at 81.28 21.59 0)
			(effects
				(font
					(size 1.27 1.27)
					(thickness 0.15)
				)
				(justify left bottom)
				(hide yes)
			)
		)
		(property "Val" "100n"
			(at 66.04 40.6335 90)
			(effects
				(font
					(size 1.27 1.27)
					(thickness 0.15)
				)
				(justify right)
			)
		)
		(property "License" "Apache-2.0"
			(at 86.36 21.59 0)
			(effects
				(font
					(size 1.27 1.27)
					(thickness 0.15)
				)
				(justify left bottom)
				(hide yes)
			)
		)
		(property "Author" "Antmicro"
			(at 88.9 21.59 0)
			(effects
				(font
					(size 1.27 1.27)
					(thickness 0.15)
				)
				(justify left bottom)
				(hide yes)
			)
		)
		(property "Voltage" "50V"
			(at 91.44 21.59 0)
			(effects
				(font
					(size 1.27 1.27)
				)
				(justify left bottom)
				(hide yes)
			)
		)
		(property "Dielectric" "X5R"
			(at 93.98 21.59 0)
			(effects
				(font
					(size 1.27 1.27)
				)
				(justify left bottom)
				(hide yes)
			)
		)
		(pin "1"
		)
		(pin "2"
		)
		(instances
			(project "k410t-devboard"
				(path ""
					(reference "C190")
					(unit 1)
				)
			)
		)
	)
	(symbol
		(lib_id "antmicropower:GND")
		(at 39.37 55.88 0)
		(unit 1)
		(exclude_from_sim no)
		(in_bom yes)
		(on_board yes)
		(dnp no)
		(fields_autoplaced yes)
		(property "Reference" "#PWR088"
			(at 39.37 62.23 0)
			(effects
				(font
					(size 1.27 1.27)
				)
				(hide yes)
			)
		)
		(property "Value" "GND"
			(at 39.37 59.69 0)
			(effects
				(font
					(size 1.27 1.27)
				)
			)
		)
		(property "Footprint" ""
			(at 48.26 63.5 0)
			(effects
				(font
					(size 1.27 1.27)
					(thickness 0.15)
				)
				(justify left bottom)
				(hide yes)
			)
		)
		(property "Datasheet" ""
			(at 48.26 68.58 0)
			(effects
				(font
					(size 1.27 1.27)
					(thickness 0.15)
				)
				(justify left bottom)
				(hide yes)
			)
		)
		(property "Description" ""
			(at 39.37 55.88 0)
			(effects
				(font
					(size 1.27 1.27)
				)
			)
		)
		(property "Author" "Antmicro"
			(at 48.26 63.5 0)
			(effects
				(font
					(size 1.27 1.27)
					(thickness 0.15)
				)
				(justify left bottom)
				(hide yes)
			)
		)
		(property "License" "Apache-2.0"
			(at 48.26 66.04 0)
			(effects
				(font
					(size 1.27 1.27)
					(thickness 0.15)
				)
				(justify left bottom)
				(hide yes)
			)
		)
		(pin "1"
		)
		(instances
			(project "k410t-devboard"
				(path ""
					(reference "#PWR088")
					(unit 1)
				)
			)
		)
	)
	(symbol
		(lib_id "antmicroCapacitors0603:C_1u_25V_0603")
		(at 350.52 208.28 90)
		(unit 1)
		(exclude_from_sim no)
		(in_bom yes)
		(on_board yes)
		(dnp no)
		(fields_autoplaced yes)
		(property "Reference" "C208"
			(at 353.06 204.4635 90)
			(effects
				(font
					(size 1.27 1.27)
				)
				(justify right)
			)
		)
		(property "Value" "C_1u_25V_0603"
			(at 360.68 187.96 0)
			(effects
				(font
					(size 1.27 1.27)
					(thickness 0.15)
				)
				(justify left bottom)
				(hide yes)
			)
		)
		(property "Footprint" "antmicro-footprints:C_0603_1608Metric"
			(at 363.22 187.96 0)
			(effects
				(font
					(size 1.27 1.27)
					(thickness 0.15)
				)
				(justify left bottom)
				(hide yes)
			)
		)
		(property "Datasheet" "https://product.samsungsem.com/mlcc/CL10A105KA8NNN.do"
			(at 365.76 187.96 0)
			(effects
				(font
					(size 1.27 1.27)
					(thickness 0.15)
				)
				(justify left bottom)
				(hide yes)
			)
		)
		(property "Description" ""
			(at 350.52 208.28 0)
			(effects
				(font
					(size 1.27 1.27)
				)
			)
		)
		(property "Manufacturer" "Samsung Electro-Mechanics"
			(at 370.84 187.96 0)
			(effects
				(font
					(size 1.27 1.27)
					(thickness 0.15)
				)
				(justify left bottom)
				(hide yes)
			)
		)
		(property "MPN" "CL10A105KA8NNNC"
			(at 368.3 187.96 0)
			(effects
				(font
					(size 1.27 1.27)
					(thickness 0.15)
				)
				(justify left bottom)
				(hide yes)
			)
		)
		(property "Val" "1u"
			(at 353.06 207.0035 90)
			(effects
				(font
					(size 1.27 1.27)
					(thickness 0.15)
				)
				(justify right)
			)
		)
		(property "License" "Apache-2.0"
			(at 373.38 187.96 0)
			(effects
				(font
					(size 1.27 1.27)
					(thickness 0.15)
				)
				(justify left bottom)
				(hide yes)
			)
		)
		(property "Author" "Antmicro"
			(at 375.92 187.96 0)
			(effects
				(font
					(size 1.27 1.27)
					(thickness 0.15)
				)
				(justify left bottom)
				(hide yes)
			)
		)
		(property "Voltage" "25V"
			(at 378.46 187.96 0)
			(effects
				(font
					(size 1.27 1.27)
				)
				(justify left bottom)
				(hide yes)
			)
		)
		(property "Dielectric" ""
			(at 381 187.96 0)
			(effects
				(font
					(size 1.27 1.27)
				)
				(justify left bottom)
				(hide yes)
			)
		)
		(pin "1"
		)
		(pin "2"
		)
		(instances
			(project "k410t-devboard"
				(path ""
					(reference "C208")
					(unit 1)
				)
			)
		)
	)
	(symbol
		(lib_id "antmicroDiodesRectifiersSingle:PMEG3050EP,115")
		(at 334.01 71.12 0)
		(unit 1)
		(exclude_from_sim no)
		(in_bom no)
		(on_board yes)
		(dnp yes)
		(property "Reference" "D16"
			(at 336.8675 64.135 0)
			(effects
				(font
					(size 1.27 1.27)
				)
			)
		)
		(property "Value" "PMEG3050EP,115"
			(at 336.8675 66.675 0)
			(effects
				(font
					(size 1.27 1.27)
					(thickness 0.15)
				)
			)
		)
		(property "Footprint" "antmicro-footprints:Nexperia_SOD128"
			(at 355.6 81.28 0)
			(effects
				(font
					(size 1.27 1.27)
					(thickness 0.15)
				)
				(justify left bottom)
				(hide yes)
			)
		)
		(property "Datasheet" "https://www.mouser.com/datasheet/2/916/PMEG3050EP-2938519.pdf"
			(at 355.6 83.82 0)
			(effects
				(font
					(size 1.27 1.27)
					(thickness 0.15)
				)
				(justify left bottom)
				(hide yes)
			)
		)
		(property "Description" ""
			(at 334.01 71.12 0)
			(effects
				(font
					(size 1.27 1.27)
				)
			)
		)
		(property "MPN" "PMEG3050EP,115"
			(at 355.6 86.36 0)
			(effects
				(font
					(size 1.27 1.27)
					(thickness 0.15)
				)
				(justify left bottom)
				(hide yes)
			)
		)
		(property "Manufacturer" "Nexperia"
			(at 355.6 88.9 0)
			(effects
				(font
					(size 1.27 1.27)
					(thickness 0.15)
				)
				(justify left bottom)
				(hide yes)
			)
		)
		(property "Author" "Antmicro"
			(at 355.6 91.44 0)
			(effects
				(font
					(size 1.27 1.27)
					(thickness 0.15)
				)
				(justify left bottom)
				(hide yes)
			)
		)
		(property "License" "Apache-2.0"
			(at 355.6 93.98 0)
			(effects
				(font
					(size 1.27 1.27)
					(thickness 0.15)
				)
				(justify left bottom)
				(hide yes)
			)
		)
		(property "DNP" "DNP"
			(at 340.36 72.39 0)
			(effects
				(font
					(size 1.27 1.27)
				)
			)
		)
		(pin "1"
		)
		(pin "2"
		)
		(instances
			(project "k410t-devboard"
				(path ""
					(reference "D16")
					(unit 1)
				)
			)
		)
	)
	(symbol
		(lib_id "antmicroResistors0402:R_1k_0402")
		(at 93.98 96.52 90)
		(unit 1)
		(exclude_from_sim no)
		(in_bom yes)
		(on_board yes)
		(dnp no)
		(fields_autoplaced yes)
		(property "Reference" "R45"
			(at 96.52 92.7099 90)
			(effects
				(font
					(size 1.27 1.27)
				)
				(justify right)
			)
		)
		(property "Value" "R_1k_0402"
			(at 106.68 76.2 0)
			(effects
				(font
					(size 1.27 1.27)
					(thickness 0.15)
				)
				(justify left bottom)
				(hide yes)
			)
		)
		(property "Footprint" "antmicro-footprints:R_0402_1005Metric"
			(at 109.22 76.2 0)
			(effects
				(font
					(size 1.27 1.27)
					(thickness 0.15)
				)
				(justify left bottom)
				(hide yes)
			)
		)
		(property "Datasheet" "https://www.bourns.com/docs/product-datasheets/cr.pdf"
			(at 111.76 76.2 0)
			(effects
				(font
					(size 1.27 1.27)
					(thickness 0.15)
				)
				(justify left bottom)
				(hide yes)
			)
		)
		(property "Description" ""
			(at 93.98 96.52 0)
			(effects
				(font
					(size 1.27 1.27)
				)
			)
		)
		(property "Manufacturer" "Bourns"
			(at 116.84 76.2 0)
			(effects
				(font
					(size 1.27 1.27)
					(thickness 0.15)
				)
				(justify left bottom)
				(hide yes)
			)
		)
		(property "MPN" "CR0402-FX-1001GLF"
			(at 114.3 76.2 0)
			(effects
				(font
					(size 1.27 1.27)
					(thickness 0.15)
				)
				(justify left bottom)
				(hide yes)
			)
		)
		(property "Val" "1k"
			(at 96.52 95.2499 90)
			(effects
				(font
					(size 1.27 1.27)
					(thickness 0.15)
				)
				(justify right)
			)
		)
		(property "License" "Apache-2.0"
			(at 119.38 76.2 0)
			(effects
				(font
					(size 1.27 1.27)
					(thickness 0.15)
				)
				(justify left bottom)
				(hide yes)
			)
		)
		(property "Author" "Antmicro"
			(at 121.92 76.2 0)
			(effects
				(font
					(size 1.27 1.27)
					(thickness 0.15)
				)
				(justify left bottom)
				(hide yes)
			)
		)
		(property "Tolerance" "1%"
			(at 104.14 76.2 0)
			(effects
				(font
					(size 1.27 1.27)
				)
				(justify left bottom)
				(hide yes)
			)
		)
		(pin "1"
		)
		(pin "2"
		)
		(instances
			(project "k410t-devboard"
				(path ""
					(reference "R45")
					(unit 1)
				)
			)
		)
	)
	(symbol
		(lib_id "antmicroResistors0402:R_1k_0402")
		(at 172.72 118.11 270)
		(unit 1)
		(exclude_from_sim no)
		(in_bom yes)
		(on_board yes)
		(dnp no)
		(property "Reference" "R58"
			(at 173.99 119.38 90)
			(effects
				(font
					(size 1.27 1.27)
				)
				(justify left)
			)
		)
		(property "Value" "R_1k_0402"
			(at 160.02 138.43 0)
			(effects
				(font
					(size 1.27 1.27)
					(thickness 0.15)
				)
				(justify left bottom)
				(hide yes)
			)
		)
		(property "Footprint" "antmicro-footprints:R_0402_1005Metric"
			(at 157.48 138.43 0)
			(effects
				(font
					(size 1.27 1.27)
					(thickness 0.15)
				)
				(justify left bottom)
				(hide yes)
			)
		)
		(property "Datasheet" "https://www.bourns.com/docs/product-datasheets/cr.pdf"
			(at 154.94 138.43 0)
			(effects
				(font
					(size 1.27 1.27)
					(thickness 0.15)
				)
				(justify left bottom)
				(hide yes)
			)
		)
		(property "Description" ""
			(at 172.72 118.11 0)
			(effects
				(font
					(size 1.27 1.27)
				)
			)
		)
		(property "Manufacturer" "Bourns"
			(at 149.86 138.43 0)
			(effects
				(font
					(size 1.27 1.27)
					(thickness 0.15)
				)
				(justify left bottom)
				(hide yes)
			)
		)
		(property "MPN" "CR0402-FX-1001GLF"
			(at 152.4 138.43 0)
			(effects
				(font
					(size 1.27 1.27)
					(thickness 0.15)
				)
				(justify left bottom)
				(hide yes)
			)
		)
		(property "Val" "1k"
			(at 173.99 121.92 90)
			(effects
				(font
					(size 1.27 1.27)
					(thickness 0.15)
				)
				(justify left)
			)
		)
		(property "License" "Apache-2.0"
			(at 147.32 138.43 0)
			(effects
				(font
					(size 1.27 1.27)
					(thickness 0.15)
				)
				(justify left bottom)
				(hide yes)
			)
		)
		(property "Author" "Antmicro"
			(at 144.78 138.43 0)
			(effects
				(font
					(size 1.27 1.27)
					(thickness 0.15)
				)
				(justify left bottom)
				(hide yes)
			)
		)
		(property "Tolerance" "1%"
			(at 162.56 138.43 0)
			(effects
				(font
					(size 1.27 1.27)
				)
				(justify left bottom)
				(hide yes)
			)
		)
		(pin "1"
		)
		(pin "2"
		)
		(instances
			(project "k410t-devboard"
				(path ""
					(reference "R58")
					(unit 1)
				)
			)
		)
	)
	(symbol
		(lib_id "antmicropower:GNDD")
		(at 177.8 271.78 0)
		(unit 1)
		(exclude_from_sim no)
		(in_bom yes)
		(on_board yes)
		(dnp no)
		(property "Reference" "#PWR0101"
			(at 177.8 278.13 0)
			(effects
				(font
					(size 1.27 1.27)
				)
				(hide yes)
			)
		)
		(property "Value" "GNDD"
			(at 177.8 275.59 0)
			(effects
				(font
					(size 1.27 1.27)
				)
			)
		)
		(property "Footprint" ""
			(at 177.8 271.78 0)
			(effects
				(font
					(size 1.27 1.27)
				)
				(hide yes)
			)
		)
		(property "Datasheet" ""
			(at 177.8 271.78 0)
			(effects
				(font
					(size 1.27 1.27)
				)
				(hide yes)
			)
		)
		(property "Description" ""
			(at 177.8 271.78 0)
			(effects
				(font
					(size 1.27 1.27)
				)
			)
		)
		(property "Author" "Antmicro"
			(at 193.04 279.4 0)
			(effects
				(font
					(size 1.27 1.27)
					(thickness 0.15)
				)
				(justify left bottom)
				(hide yes)
			)
		)
		(property "License" "Apache-2.0"
			(at 193.04 281.94 0)
			(effects
				(font
					(size 1.27 1.27)
					(thickness 0.15)
				)
				(justify left bottom)
				(hide yes)
			)
		)
		(pin "1"
		)
		(instances
			(project "k410t-devboard"
				(path ""
					(reference "#PWR0101")
					(unit 1)
				)
			)
		)
	)
	(symbol
		(lib_id "antmicroTVSDiodes:PTVS58VS1UR,115")
		(at 120.65 240.03 90)
		(mirror x)
		(unit 1)
		(exclude_from_sim no)
		(in_bom yes)
		(on_board yes)
		(dnp no)
		(property "Reference" "D10"
			(at 118.11 241.3 90)
			(effects
				(font
					(size 1.27 1.27)
				)
				(justify left)
			)
		)
		(property "Value" "PTVS58VS1UR,115"
			(at 135.89 261.62 0)
			(effects
				(font
					(size 1.27 1.27)
					(thickness 0.15)
				)
				(justify left bottom)
				(hide yes)
			)
		)
		(property "Footprint" "antmicro-footprints:D_SOD-123F"
			(at 130.81 261.62 0)
			(effects
				(font
					(size 1.27 1.27)
					(thickness 0.15)
				)
				(justify left bottom)
				(hide yes)
			)
		)
		(property "Datasheet" "https://assets.nexperia.com/documents/data-sheet/PTVSXS1UR_SER.pdf"
			(at 133.35 261.62 0)
			(effects
				(font
					(size 1.27 1.27)
					(thickness 0.15)
				)
				(justify left bottom)
				(hide yes)
			)
		)
		(property "Description" ""
			(at 120.65 240.03 0)
			(effects
				(font
					(size 1.27 1.27)
				)
			)
		)
		(property "MPN" "PTVS58VS1UR,115"
			(at 118.11 243.84 90)
			(effects
				(font
					(size 1.27 1.27)
					(thickness 0.15)
				)
				(justify left)
			)
		)
		(property "Manufacturer" "Nexperia"
			(at 138.43 261.62 0)
			(effects
				(font
					(size 1.27 1.27)
					(thickness 0.15)
				)
				(justify left bottom)
				(hide yes)
			)
		)
		(property "Author" "Antmicro"
			(at 140.97 261.62 0)
			(effects
				(font
					(size 1.27 1.27)
					(thickness 0.15)
				)
				(justify left bottom)
				(hide yes)
			)
		)
		(property "License" "Apache-2.0"
			(at 143.51 261.62 0)
			(effects
				(font
					(size 1.27 1.27)
					(thickness 0.15)
				)
				(justify left bottom)
				(hide yes)
			)
		)
		(property "Public" "False"
			(at 138.43 260.35 0)
			(effects
				(font
					(size 1.27 1.27)
				)
				(justify left bottom)
				(hide yes)
			)
		)
		(pin "1"
		)
		(pin "2"
		)
		(instances
			(project "k410t-devboard"
				(path ""
					(reference "D10")
					(unit 1)
				)
			)
		)
	)
	(symbol
		(lib_id "antmicroCapacitorsmisc:C_100n_100V_0805")
		(at 156.845 96.52 180)
		(unit 1)
		(exclude_from_sim no)
		(in_bom yes)
		(on_board yes)
		(dnp no)
		(fields_autoplaced yes)
		(property "Reference" "C198"
			(at 154.2986 87.63 0)
			(effects
				(font
					(size 1.27 1.27)
				)
			)
		)
		(property "Value" "C_100n_100V_0805"
			(at 156.845 92.71 0)
			(effects
				(font
					(size 1.27 1.27)
				)
				(hide yes)
			)
		)
		(property "Footprint" "antmicro-footprints:C_0805_2012Metric"
			(at 151.765 101.6 0)
			(effects
				(font
					(size 1.27 1.27)
				)
				(justify left)
				(hide yes)
			)
		)
		(property "Datasheet" "https://product.samsungsem.com/mlcc/CL21B104KCFNNN.do"
			(at 156.845 96.52 0)
			(effects
				(font
					(size 1.27 1.27)
				)
				(hide yes)
			)
		)
		(property "Description" ""
			(at 156.845 96.52 0)
			(effects
				(font
					(size 1.27 1.27)
				)
			)
		)
		(property "Manufacturer" "Samsung Electro-Mechanics"
			(at 151.765 106.68 0)
			(effects
				(font
					(size 1.27 1.27)
				)
				(justify left)
				(hide yes)
			)
		)
		(property "MPN" "CL21B104KCFNNNE"
			(at 151.765 104.14 0)
			(effects
				(font
					(size 1.27 1.27)
				)
				(justify left)
				(hide yes)
			)
		)
		(property "Val" "100n"
			(at 154.2986 90.17 0)
			(effects
				(font
					(size 1.27 1.27)
				)
			)
		)
		(property "License" "Apache-2.0"
			(at 136.525 73.66 0)
			(effects
				(font
					(size 1.27 1.27)
					(thickness 0.15)
				)
				(justify left bottom)
				(hide yes)
			)
		)
		(property "Author" "Antmicro"
			(at 136.525 71.12 0)
			(effects
				(font
					(size 1.27 1.27)
					(thickness 0.15)
				)
				(justify left bottom)
				(hide yes)
			)
		)
		(property "Voltage" "100V"
			(at 154.2986 92.71 0)
			(effects
				(font
					(size 1.27 1.27)
				)
			)
		)
		(property "Dielectric" "X7R"
			(at 136.525 66.04 0)
			(effects
				(font
					(size 1.27 1.27)
				)
				(justify left bottom)
				(hide yes)
			)
		)
		(pin "1"
		)
		(pin "2"
		)
		(instances
			(project "k410t-devboard"
				(path ""
					(reference "C198")
					(unit 1)
				)
			)
		)
	)
	(symbol
		(lib_id "antmicroTVSDiodes:ESDA25P35-1U1M")
		(at 76.2 38.1 90)
		(mirror x)
		(unit 1)
		(exclude_from_sim no)
		(in_bom yes)
		(on_board yes)
		(dnp no)
		(property "Reference" "D3"
			(at 78.74 42.2275 90)
			(effects
				(font
					(size 1.27 1.27)
				)
				(justify right)
			)
		)
		(property "Value" "ESDA25P35-1U1M"
			(at 78.74 39.6876 90)
			(effects
				(font
					(size 1.27 1.27)
					(thickness 0.15)
				)
				(justify right)
				(hide yes)
			)
		)
		(property "Footprint" "antmicro-footprints:QFN-2L_1.6x1x0.55mm"
			(at 86.36 62.23 0)
			(effects
				(font
					(size 1.27 1.27)
					(thickness 0.15)
				)
				(justify left bottom)
				(hide yes)
			)
		)
		(property "Datasheet" "https://www.st.com/resource/en/datasheet/esda25p35-1u1m.pdf"
			(at 88.9 62.23 0)
			(effects
				(font
					(size 1.27 1.27)
					(thickness 0.15)
				)
				(justify left bottom)
				(hide yes)
			)
		)
		(property "Description" ""
			(at 76.2 38.1 0)
			(effects
				(font
					(size 1.27 1.27)
				)
			)
		)
		(property "MPN" "ESDA25P35-1U1M"
			(at 78.74 39.6875 90)
			(effects
				(font
					(size 1.27 1.27)
					(thickness 0.15)
				)
				(justify right)
			)
		)
		(property "Manufacturer" "STMicroelectronics"
			(at 93.98 62.23 0)
			(effects
				(font
					(size 1.27 1.27)
					(thickness 0.15)
				)
				(justify left bottom)
				(hide yes)
			)
		)
		(property "Author" "Antmicro"
			(at 96.52 62.23 0)
			(effects
				(font
					(size 1.27 1.27)
					(thickness 0.15)
				)
				(justify left bottom)
				(hide yes)
			)
		)
		(property "License" "Apache-2.0"
			(at 99.06 62.23 0)
			(effects
				(font
					(size 1.27 1.27)
					(thickness 0.15)
				)
				(justify left bottom)
				(hide yes)
			)
		)
		(property "Public" "False"
			(at 93.98 58.42 0)
			(effects
				(font
					(size 1.27 1.27)
				)
				(justify left bottom)
				(hide yes)
			)
		)
		(pin "1"
		)
		(pin "2"
		)
		(instances
			(project "k410t-devboard"
				(path ""
					(reference "D3")
					(unit 1)
				)
			)
		)
	)
	(symbol
		(lib_id "antmicropower:PWR_FLAG")
		(at 182.88 76.2 0)
		(unit 1)
		(exclude_from_sim no)
		(in_bom yes)
		(on_board yes)
		(dnp no)
		(fields_autoplaced yes)
		(property "Reference" "#FLG02"
			(at 182.88 74.295 0)
			(effects
				(font
					(size 1.27 1.27)
				)
				(hide yes)
			)
		)
		(property "Value" "PWR_FLAG"
			(at 182.88 72.6242 0)
			(effects
				(font
					(size 1.27 1.27)
				)
			)
		)
		(property "Footprint" ""
			(at 182.88 76.2 0)
			(effects
				(font
					(size 1.27 1.27)
				)
				(hide yes)
			)
		)
		(property "Datasheet" ""
			(at 182.88 76.2 0)
			(effects
				(font
					(size 1.27 1.27)
				)
				(hide yes)
			)
		)
		(property "Description" ""
			(at 182.88 76.2 0)
			(effects
				(font
					(size 1.27 1.27)
				)
			)
		)
		(pin "1"
		)
		(instances
			(project "k410t-devboard"
				(path ""
					(reference "#FLG02")
					(unit 1)
				)
			)
		)
	)
	(symbol
		(lib_id "antmicroCapacitors0402:C_100n_0402")
		(at 303.53 208.28 90)
		(unit 1)
		(exclude_from_sim no)
		(in_bom yes)
		(on_board yes)
		(dnp no)
		(fields_autoplaced yes)
		(property "Reference" "C205"
			(at 300.99 204.4635 90)
			(effects
				(font
					(size 1.27 1.27)
				)
				(justify left)
			)
		)
		(property "Value" "C_100n_0402"
			(at 313.69 187.96 0)
			(effects
				(font
					(size 1.27 1.27)
					(thickness 0.15)
				)
				(justify left bottom)
				(hide yes)
			)
		)
		(property "Footprint" "antmicro-footprints:C_0402_1005Metric"
			(at 316.23 187.96 0)
			(effects
				(font
					(size 1.27 1.27)
					(thickness 0.15)
				)
				(justify left bottom)
				(hide yes)
			)
		)
		(property "Datasheet" "https://www.murata.com/products/productdetail?partno=GRM155R61H104KE14%23"
			(at 318.77 187.96 0)
			(effects
				(font
					(size 1.27 1.27)
					(thickness 0.15)
				)
				(justify left bottom)
				(hide yes)
			)
		)
		(property "Description" ""
			(at 303.53 208.28 0)
			(effects
				(font
					(size 1.27 1.27)
				)
			)
		)
		(property "Manufacturer" "Murata"
			(at 323.85 187.96 0)
			(effects
				(font
					(size 1.27 1.27)
					(thickness 0.15)
				)
				(justify left bottom)
				(hide yes)
			)
		)
		(property "MPN" "GRM155R61H104KE14D"
			(at 321.31 187.96 0)
			(effects
				(font
					(size 1.27 1.27)
					(thickness 0.15)
				)
				(justify left bottom)
				(hide yes)
			)
		)
		(property "Val" "100n"
			(at 300.99 207.0035 90)
			(effects
				(font
					(size 1.27 1.27)
					(thickness 0.15)
				)
				(justify left)
			)
		)
		(property "License" "Apache-2.0"
			(at 326.39 187.96 0)
			(effects
				(font
					(size 1.27 1.27)
					(thickness 0.15)
				)
				(justify left bottom)
				(hide yes)
			)
		)
		(property "Author" "Antmicro"
			(at 328.93 187.96 0)
			(effects
				(font
					(size 1.27 1.27)
					(thickness 0.15)
				)
				(justify left bottom)
				(hide yes)
			)
		)
		(property "Voltage" "50V"
			(at 331.47 187.96 0)
			(effects
				(font
					(size 1.27 1.27)
				)
				(justify left bottom)
				(hide yes)
			)
		)
		(property "Dielectric" "X5R"
			(at 334.01 187.96 0)
			(effects
				(font
					(size 1.27 1.27)
				)
				(justify left bottom)
				(hide yes)
			)
		)
		(pin "1"
		)
		(pin "2"
		)
		(instances
			(project "k410t-devboard"
				(path ""
					(reference "C205")
					(unit 1)
				)
			)
		)
	)
	(symbol
		(lib_id "antmicroCapacitorsmisc:C_22u_100V_2220")
		(at 144.78 198.12 90)
		(unit 1)
		(exclude_from_sim no)
		(in_bom yes)
		(on_board yes)
		(dnp no)
		(property "Reference" "C196"
			(at 144.78 193.04 90)
			(effects
				(font
					(size 1.27 1.27)
				)
				(justify right)
			)
		)
		(property "Value" "C_22u_100V_2220"
			(at 154.94 177.8 0)
			(effects
				(font
					(size 1.27 1.27)
					(thickness 0.15)
				)
				(justify left bottom)
				(hide yes)
			)
		)
		(property "Footprint" "antmicro-footprints:C_2220_5650Metric"
			(at 157.48 177.8 0)
			(effects
				(font
					(size 1.27 1.27)
					(thickness 0.15)
				)
				(justify left bottom)
				(hide yes)
			)
		)
		(property "Datasheet" "https://product.tdk.com/en/search/capacitor/ceramic/mlcc/info?part_no=C5750X7S2A226M280KB"
			(at 160.02 177.8 0)
			(effects
				(font
					(size 1.27 1.27)
					(thickness 0.15)
				)
				(justify left bottom)
				(hide yes)
			)
		)
		(property "Description" ""
			(at 144.78 198.12 0)
			(effects
				(font
					(size 1.27 1.27)
				)
			)
		)
		(property "Manufacturer" "TDK"
			(at 165.1 177.8 0)
			(effects
				(font
					(size 1.27 1.27)
					(thickness 0.15)
				)
				(justify left bottom)
				(hide yes)
			)
		)
		(property "MPN" "C5750X7S2A226M280KB"
			(at 162.56 177.8 0)
			(effects
				(font
					(size 1.27 1.27)
					(thickness 0.15)
				)
				(justify left bottom)
				(hide yes)
			)
		)
		(property "Val" "22u"
			(at 144.78 198.12 90)
			(effects
				(font
					(size 1.27 1.27)
					(thickness 0.15)
				)
				(justify right)
			)
		)
		(property "License" "Apache-2.0"
			(at 167.64 177.8 0)
			(effects
				(font
					(size 1.27 1.27)
					(thickness 0.15)
				)
				(justify left bottom)
				(hide yes)
			)
		)
		(property "Author" "Antmicro"
			(at 170.18 177.8 0)
			(effects
				(font
					(size 1.27 1.27)
					(thickness 0.15)
				)
				(justify left bottom)
				(hide yes)
			)
		)
		(property "Voltage" "100V"
			(at 144.78 200.66 90)
			(effects
				(font
					(size 1.27 1.27)
				)
				(justify right)
			)
		)
		(property "Dielectric" "X7S"
			(at 175.26 177.8 0)
			(effects
				(font
					(size 1.27 1.27)
				)
				(justify left bottom)
				(hide yes)
			)
		)
		(pin "1"
		)
		(pin "2"
		)
		(instances
			(project "k410t-devboard"
				(path ""
					(reference "C196")
					(unit 1)
				)
			)
		)
	)
	(symbol
		(lib_id "antmicroPMICORControllersIdealDiodes:LTC4412IS6")
		(at 314.96 93.98 0)
		(unit 1)
		(exclude_from_sim no)
		(in_bom yes)
		(on_board yes)
		(dnp no)
		(fields_autoplaced yes)
		(property "Reference" "U10"
			(at 323.85 86.36 0)
			(effects
				(font
					(size 1.27 1.27)
				)
			)
		)
		(property "Value" "LTC4412IS6"
			(at 323.85 90.17 0)
			(effects
				(font
					(size 1.27 1.27)
					(thickness 0.15)
				)
				(hide yes)
			)
		)
		(property "Footprint" "antmicro-footprints:SOT-23-6"
			(at 346.71 101.6 0)
			(effects
				(font
					(size 1.27 1.27)
					(thickness 0.15)
				)
				(justify left bottom)
				(hide yes)
			)
		)
		(property "Datasheet" "https://www.mouser.com/datasheet/2/308/NCV8187_D-1813214.pdf"
			(at 346.71 104.14 0)
			(effects
				(font
					(size 1.27 1.27)
					(thickness 0.15)
				)
				(justify left bottom)
				(hide yes)
			)
		)
		(property "Description" ""
			(at 314.96 93.98 0)
			(effects
				(font
					(size 1.27 1.27)
				)
			)
		)
		(property "MPN" "LTC4412IS6#TRMPBF"
			(at 323.85 88.9 0)
			(effects
				(font
					(size 1.27 1.27)
					(thickness 0.15)
				)
			)
		)
		(property "Manufacturer" "Analog Devices"
			(at 346.71 109.22 0)
			(effects
				(font
					(size 1.27 1.27)
					(thickness 0.15)
				)
				(justify left bottom)
				(hide yes)
			)
		)
		(property "Author" "Antmicro"
			(at 346.71 111.76 0)
			(effects
				(font
					(size 1.27 1.27)
					(thickness 0.15)
				)
				(justify left bottom)
				(hide yes)
			)
		)
		(property "License" "Apache-2.0"
			(at 346.71 114.3 0)
			(effects
				(font
					(size 1.27 1.27)
					(thickness 0.15)
				)
				(justify left bottom)
				(hide yes)
			)
		)
		(pin "1"
		)
		(pin "2"
		)
		(pin "3"
		)
		(pin "4"
		)
		(pin "5"
		)
		(pin "6"
		)
		(instances
			(project "k410t-devboard"
				(path ""
					(reference "U10")
					(unit 1)
				)
			)
		)
	)
	(symbol
		(lib_id "antmicroResistors0402:R_10k_0402")
		(at 184.15 265.43 90)
		(unit 1)
		(exclude_from_sim no)
		(in_bom yes)
		(on_board yes)
		(dnp no)
		(fields_autoplaced yes)
		(property "Reference" "R167"
			(at 186.69 261.6199 90)
			(effects
				(font
					(size 1.27 1.27)
				)
				(justify right)
			)
		)
		(property "Value" "R_10k_0402"
			(at 196.85 245.11 0)
			(effects
				(font
					(size 1.27 1.27)
					(thickness 0.15)
				)
				(justify left bottom)
				(hide yes)
			)
		)
		(property "Footprint" "antmicro-footprints:R_0402_1005Metric"
			(at 199.39 245.11 0)
			(effects
				(font
					(size 1.27 1.27)
					(thickness 0.15)
				)
				(justify left bottom)
				(hide yes)
			)
		)
		(property "Datasheet" "https://www.bourns.com/docs/product-datasheets/cr.pdf"
			(at 201.93 245.11 0)
			(effects
				(font
					(size 1.27 1.27)
					(thickness 0.15)
				)
				(justify left bottom)
				(hide yes)
			)
		)
		(property "Description" ""
			(at 184.15 265.43 0)
			(effects
				(font
					(size 1.27 1.27)
				)
			)
		)
		(property "Manufacturer" "Bourns"
			(at 207.01 245.11 0)
			(effects
				(font
					(size 1.27 1.27)
					(thickness 0.15)
				)
				(justify left bottom)
				(hide yes)
			)
		)
		(property "MPN" "CR0402-FX-1002GLF"
			(at 204.47 245.11 0)
			(effects
				(font
					(size 1.27 1.27)
					(thickness 0.15)
				)
				(justify left bottom)
				(hide yes)
			)
		)
		(property "Val" "10k"
			(at 186.69 264.1599 90)
			(effects
				(font
					(size 1.27 1.27)
					(thickness 0.15)
				)
				(justify right)
			)
		)
		(property "License" "Apache-2.0"
			(at 209.55 245.11 0)
			(effects
				(font
					(size 1.27 1.27)
					(thickness 0.15)
				)
				(justify left bottom)
				(hide yes)
			)
		)
		(property "Author" "Antmicro"
			(at 212.09 245.11 0)
			(effects
				(font
					(size 1.27 1.27)
					(thickness 0.15)
				)
				(justify left bottom)
				(hide yes)
			)
		)
		(property "Tolerance" "1%"
			(at 194.31 245.11 0)
			(effects
				(font
					(size 1.27 1.27)
				)
				(justify left bottom)
				(hide yes)
			)
		)
		(pin "1"
		)
		(pin "2"
		)
		(instances
			(project "k410t-devboard"
				(path ""
					(reference "R167")
					(unit 1)
				)
			)
		)
	)
	(symbol
		(lib_id "antmicroCapacitors0603:C_1u_25V_0603")
		(at 181.61 147.32 90)
		(mirror x)
		(unit 1)
		(exclude_from_sim no)
		(in_bom yes)
		(on_board yes)
		(dnp no)
		(property "Reference" "C191"
			(at 182.245 147.955 90)
			(effects
				(font
					(size 1.27 1.27)
				)
				(justify right)
			)
		)
		(property "Value" "C_1u_25V_0603"
			(at 191.77 167.64 0)
			(effects
				(font
					(size 1.27 1.27)
					(thickness 0.15)
				)
				(justify left bottom)
				(hide yes)
			)
		)
		(property "Footprint" "antmicro-footprints:C_0603_1608Metric"
			(at 194.31 167.64 0)
			(effects
				(font
					(size 1.27 1.27)
					(thickness 0.15)
				)
				(justify left bottom)
				(hide yes)
			)
		)
		(property "Datasheet" "https://product.samsungsem.com/mlcc/CL10A105KA8NNN.do"
			(at 196.85 167.64 0)
			(effects
				(font
					(size 1.27 1.27)
					(thickness 0.15)
				)
				(justify left bottom)
				(hide yes)
			)
		)
		(property "Description" ""
			(at 181.61 147.32 0)
			(effects
				(font
					(size 1.27 1.27)
				)
			)
		)
		(property "Manufacturer" "Samsung Electro-Mechanics"
			(at 201.93 167.64 0)
			(effects
				(font
					(size 1.27 1.27)
					(thickness 0.15)
				)
				(justify left bottom)
				(hide yes)
			)
		)
		(property "MPN" "CL10A105KA8NNNC"
			(at 199.39 167.64 0)
			(effects
				(font
					(size 1.27 1.27)
					(thickness 0.15)
				)
				(justify left bottom)
				(hide yes)
			)
		)
		(property "Val" "1u"
			(at 182.245 151.765 90)
			(effects
				(font
					(size 1.27 1.27)
					(thickness 0.15)
				)
				(justify right)
			)
		)
		(property "License" "Apache-2.0"
			(at 204.47 167.64 0)
			(effects
				(font
					(size 1.27 1.27)
					(thickness 0.15)
				)
				(justify left bottom)
				(hide yes)
			)
		)
		(property "Author" "Antmicro"
			(at 207.01 167.64 0)
			(effects
				(font
					(size 1.27 1.27)
					(thickness 0.15)
				)
				(justify left bottom)
				(hide yes)
			)
		)
		(property "Voltage" "25V"
			(at 209.55 167.64 0)
			(effects
				(font
					(size 1.27 1.27)
				)
				(justify left bottom)
				(hide yes)
			)
		)
		(property "Dielectric" ""
			(at 212.09 167.64 0)
			(effects
				(font
					(size 1.27 1.27)
				)
				(justify left bottom)
				(hide yes)
			)
		)
		(pin "1"
		)
		(pin "2"
		)
		(instances
			(project "k410t-devboard"
				(path ""
					(reference "C191")
					(unit 1)
				)
			)
		)
	)
	(symbol
		(lib_id "antmicroLEDIndicationDiscrete:LED_R_0603_KP-1608EC")
		(at 172.72 102.87 90)
		(unit 1)
		(exclude_from_sim no)
		(in_bom yes)
		(on_board yes)
		(dnp no)
		(fields_autoplaced yes)
		(property "Reference" "D13"
			(at 175.26 99.06 90)
			(effects
				(font
					(size 1.27 1.27)
				)
				(justify right)
			)
		)
		(property "Value" "LED_R_0603_KP-1608EC"
			(at 168.91 97.7901 90)
			(effects
				(font
					(size 1.27 1.27)
					(thickness 0.15)
				)
				(justify left)
				(hide yes)
			)
		)
		(property "Footprint" "antmicro-footprints:LED_0603_1608Metric_R"
			(at 182.88 80.01 0)
			(effects
				(font
					(size 1.27 1.27)
					(thickness 0.15)
				)
				(justify left bottom)
				(hide yes)
			)
		)
		(property "Datasheet" "http://www.kingbright.com/attachments/file/psearch/000/00/20131112/KP-1608EC(Ver.14A).pdf"
			(at 185.42 80.01 0)
			(effects
				(font
					(size 1.27 1.27)
					(thickness 0.15)
				)
				(justify left bottom)
				(hide yes)
			)
		)
		(property "Description" ""
			(at 172.72 102.87 0)
			(effects
				(font
					(size 1.27 1.27)
				)
			)
		)
		(property "MPN" "KP-1608EC"
			(at 187.96 80.01 0)
			(effects
				(font
					(size 1.27 1.27)
					(thickness 0.15)
				)
				(justify left bottom)
				(hide yes)
			)
		)
		(property "Manufacturer" "Kingbright"
			(at 190.5 80.01 0)
			(effects
				(font
					(size 1.27 1.27)
					(thickness 0.15)
				)
				(justify left bottom)
				(hide yes)
			)
		)
		(property "Author" "Antmicro"
			(at 193.04 80.01 0)
			(effects
				(font
					(size 1.27 1.27)
					(thickness 0.15)
				)
				(justify left bottom)
				(hide yes)
			)
		)
		(property "License" "Apache-2.0"
			(at 195.58 80.01 0)
			(effects
				(font
					(size 1.27 1.27)
					(thickness 0.15)
				)
				(justify left bottom)
				(hide yes)
			)
		)
		(property "Color" "Red"
			(at 175.26 101.6 90)
			(effects
				(font
					(size 1.27 1.27)
				)
				(justify right)
			)
		)
		(property "Public" "False"
			(at 190.5 82.55 0)
			(effects
				(font
					(size 1.27 1.27)
				)
				(justify left bottom)
				(hide yes)
			)
		)
		(pin "1"
		)
		(pin "2"
		)
		(instances
			(project "k410t-devboard"
				(path ""
					(reference "D13")
					(unit 1)
				)
			)
		)
	)
	(symbol
		(lib_id "antmicropower:GNDD")
		(at 144.78 208.28 0)
		(unit 1)
		(exclude_from_sim no)
		(in_bom yes)
		(on_board yes)
		(dnp no)
		(property "Reference" "#PWR096"
			(at 144.78 214.63 0)
			(effects
				(font
					(size 1.27 1.27)
				)
				(hide yes)
			)
		)
		(property "Value" "GNDD"
			(at 144.78 212.09 0)
			(effects
				(font
					(size 1.27 1.27)
				)
			)
		)
		(property "Footprint" ""
			(at 144.78 208.28 0)
			(effects
				(font
					(size 1.27 1.27)
				)
				(hide yes)
			)
		)
		(property "Datasheet" ""
			(at 144.78 208.28 0)
			(effects
				(font
					(size 1.27 1.27)
				)
				(hide yes)
			)
		)
		(property "Description" ""
			(at 144.78 208.28 0)
			(effects
				(font
					(size 1.27 1.27)
				)
			)
		)
		(property "Author" "Antmicro"
			(at 160.02 215.9 0)
			(effects
				(font
					(size 1.27 1.27)
					(thickness 0.15)
				)
				(justify left bottom)
				(hide yes)
			)
		)
		(property "License" "Apache-2.0"
			(at 160.02 218.44 0)
			(effects
				(font
					(size 1.27 1.27)
					(thickness 0.15)
				)
				(justify left bottom)
				(hide yes)
			)
		)
		(pin "1"
		)
		(instances
			(project "k410t-devboard"
				(path ""
					(reference "#PWR096")
					(unit 1)
				)
			)
		)
	)
	(symbol
		(lib_id "antmicroCapacitorsmisc:C_47u_16V_1206")
		(at 217.17 198.12 90)
		(unit 1)
		(exclude_from_sim no)
		(in_bom yes)
		(on_board yes)
		(dnp no)
		(property "Reference" "C201"
			(at 217.17 193.04 90)
			(effects
				(font
					(size 1.27 1.27)
				)
				(justify right)
			)
		)
		(property "Value" "C_47u_16V_1206"
			(at 227.33 177.8 0)
			(effects
				(font
					(size 1.27 1.27)
					(thickness 0.15)
				)
				(justify left bottom)
				(hide yes)
			)
		)
		(property "Footprint" "antmicro-footprints:C_1206_3216Metric"
			(at 229.87 177.8 0)
			(effects
				(font
					(size 1.27 1.27)
					(thickness 0.15)
				)
				(justify left bottom)
				(hide yes)
			)
		)
		(property "Datasheet" "https://product.tdk.com/en/search/capacitor/ceramic/mlcc/info?part_no=C3216X5R1C476M160AB"
			(at 232.41 177.8 0)
			(effects
				(font
					(size 1.27 1.27)
					(thickness 0.15)
				)
				(justify left bottom)
				(hide yes)
			)
		)
		(property "Description" ""
			(at 217.17 198.12 0)
			(effects
				(font
					(size 1.27 1.27)
				)
			)
		)
		(property "Manufacturer" "TDK"
			(at 237.49 177.8 0)
			(effects
				(font
					(size 1.27 1.27)
					(thickness 0.15)
				)
				(justify left bottom)
				(hide yes)
			)
		)
		(property "MPN" "C3216X5R1C476M160AB"
			(at 234.95 177.8 0)
			(effects
				(font
					(size 1.27 1.27)
					(thickness 0.15)
				)
				(justify left bottom)
				(hide yes)
			)
		)
		(property "Val" "47u"
			(at 217.17 198.12 90)
			(effects
				(font
					(size 1.27 1.27)
					(thickness 0.15)
				)
				(justify right)
			)
		)
		(property "License" "Apache-2.0"
			(at 240.03 177.8 0)
			(effects
				(font
					(size 1.27 1.27)
					(thickness 0.15)
				)
				(justify left bottom)
				(hide yes)
			)
		)
		(property "Author" "Antmicro"
			(at 242.57 177.8 0)
			(effects
				(font
					(size 1.27 1.27)
					(thickness 0.15)
				)
				(justify left bottom)
				(hide yes)
			)
		)
		(property "Voltage" "16V"
			(at 217.17 200.66 90)
			(effects
				(font
					(size 1.27 1.27)
				)
				(justify right)
			)
		)
		(property "Dielectric" "X5R"
			(at 247.65 177.8 0)
			(effects
				(font
					(size 1.27 1.27)
				)
				(justify left bottom)
				(hide yes)
			)
		)
		(pin "1"
		)
		(pin "2"
		)
		(instances
			(project "k410t-devboard"
				(path ""
					(reference "C201")
					(unit 1)
				)
			)
		)
	)
	(symbol
		(lib_id "antmicroTransistorsFETsMOSFETsSingle:SI7613DN-T1-GE3")
		(at 339.09 198.12 90)
		(unit 1)
		(exclude_from_sim no)
		(in_bom yes)
		(on_board yes)
		(dnp no)
		(fields_autoplaced yes)
		(property "Reference" "Q7"
			(at 336.55 184.15 90)
			(effects
				(font
					(size 1.27 1.27)
				)
			)
		)
		(property "Value" "SI7613DN-T1-GE3"
			(at 336.55 185.42 90)
			(effects
				(font
					(size 1.27 1.27)
					(thickness 0.15)
				)
				(hide yes)
			)
		)
		(property "Footprint" "antmicro-footprints:Vishay_PowerPAK_1212-8_Single"
			(at 337.82 182.88 0)
			(effects
				(font
					(size 1.27 1.27)
					(thickness 0.15)
				)
				(justify left bottom)
				(hide yes)
			)
		)
		(property "Datasheet" "https://www.vishay.com/docs/64809/si7613dn.pdf"
			(at 340.36 182.88 0)
			(effects
				(font
					(size 1.27 1.27)
					(thickness 0.15)
				)
				(justify left bottom)
				(hide yes)
			)
		)
		(property "Description" ""
			(at 339.09 198.12 0)
			(effects
				(font
					(size 1.27 1.27)
				)
			)
		)
		(property "MPN" "SI7613DN-T1-GE3"
			(at 336.55 186.69 90)
			(effects
				(font
					(size 1.27 1.27)
					(thickness 0.15)
				)
			)
		)
		(property "Manufacturer" "Vishay"
			(at 346.71 182.88 0)
			(effects
				(font
					(size 1.27 1.27)
					(thickness 0.15)
				)
				(justify left bottom)
				(hide yes)
			)
		)
		(property "Author" "Antmicro"
			(at 349.25 182.88 0)
			(effects
				(font
					(size 1.27 1.27)
					(thickness 0.15)
				)
				(justify left bottom)
				(hide yes)
			)
		)
		(property "License" "Apache-2.0"
			(at 351.79 182.88 0)
			(effects
				(font
					(size 1.27 1.27)
					(thickness 0.15)
				)
				(justify left bottom)
				(hide yes)
			)
		)
		(pin "1"
		)
		(pin "2"
		)
		(pin "3"
		)
		(pin "4"
		)
		(pin "5"
		)
		(instances
			(project "k410t-devboard"
				(path ""
					(reference "Q7")
					(unit 1)
				)
			)
		)
	)
	(symbol
		(lib_id "antmicropower:GNDD")
		(at 175.26 207.01 0)
		(unit 1)
		(exclude_from_sim no)
		(in_bom yes)
		(on_board yes)
		(dnp no)
		(property "Reference" "#PWR0100"
			(at 175.26 213.36 0)
			(effects
				(font
					(size 1.27 1.27)
				)
				(hide yes)
			)
		)
		(property "Value" "GNDD"
			(at 175.26 210.82 0)
			(effects
				(font
					(size 1.27 1.27)
				)
			)
		)
		(property "Footprint" ""
			(at 175.26 207.01 0)
			(effects
				(font
					(size 1.27 1.27)
				)
				(hide yes)
			)
		)
		(property "Datasheet" ""
			(at 175.26 207.01 0)
			(effects
				(font
					(size 1.27 1.27)
				)
				(hide yes)
			)
		)
		(property "Description" ""
			(at 175.26 207.01 0)
			(effects
				(font
					(size 1.27 1.27)
				)
			)
		)
		(property "Author" "Antmicro"
			(at 190.5 214.63 0)
			(effects
				(font
					(size 1.27 1.27)
					(thickness 0.15)
				)
				(justify left bottom)
				(hide yes)
			)
		)
		(property "License" "Apache-2.0"
			(at 190.5 217.17 0)
			(effects
				(font
					(size 1.27 1.27)
					(thickness 0.15)
				)
				(justify left bottom)
				(hide yes)
			)
		)
		(pin "1"
		)
		(instances
			(project "k410t-devboard"
				(path ""
					(reference "#PWR0100")
					(unit 1)
				)
			)
		)
	)
	(symbol
		(lib_id "antmicroFerriteBeadsandChips:FB_220Z_2A_Murata-BLM21PG_0805")
		(at 78.74 236.22 0)
		(unit 1)
		(exclude_from_sim no)
		(in_bom no)
		(on_board yes)
		(dnp yes)
		(fields_autoplaced yes)
		(property "Reference" "FB3"
			(at 81.2419 227.33 0)
			(effects
				(font
					(size 1.27 1.27)
				)
			)
		)
		(property "Value" "FB_220Z_2A_Murata-BLM21PG_0805"
			(at 81.2419 229.235 0)
			(effects
				(font
					(size 1.27 1.27)
					(thickness 0.15)
				)
				(hide yes)
			)
		)
		(property "Footprint" "antmicro-footprints:FB_0805_2012Metric"
			(at 92.71 241.3 0)
			(effects
				(font
					(size 1.27 1.27)
					(thickness 0.15)
				)
				(justify left bottom)
				(hide yes)
			)
		)
		(property "Datasheet" "https://www.murata.com/products/productdata/8796738977822/ENFA0005.pdf?1653276712000"
			(at 92.71 243.84 0)
			(effects
				(font
					(size 1.27 1.27)
					(thickness 0.15)
				)
				(justify left bottom)
				(hide yes)
			)
		)
		(property "Description" ""
			(at 78.74 236.22 0)
			(effects
				(font
					(size 1.27 1.27)
				)
			)
		)
		(property "MPN" "BLM21PG221SN1D"
			(at 92.71 246.38 0)
			(effects
				(font
					(size 1.27 1.27)
					(thickness 0.15)
				)
				(justify left bottom)
				(hide yes)
			)
		)
		(property "Manufacturer" "Murata"
			(at 92.71 248.92 0)
			(effects
				(font
					(size 1.27 1.27)
					(thickness 0.15)
				)
				(justify left bottom)
				(hide yes)
			)
		)
		(property "Author" "Antmicro"
			(at 92.71 251.46 0)
			(effects
				(font
					(size 1.27 1.27)
					(thickness 0.15)
				)
				(justify left bottom)
				(hide yes)
			)
		)
		(property "License" "Apache-2.0"
			(at 92.71 254 0)
			(effects
				(font
					(size 1.27 1.27)
					(thickness 0.15)
				)
				(justify left bottom)
				(hide yes)
			)
		)
		(property "DNP" "DNP"
			(at 81.2419 229.87 0)
			(effects
				(font
					(size 1.27 1.27)
				)
			)
		)
		(property "Val" "220Z/2A"
			(at 81.2419 232.41 0)
			(effects
				(font
					(size 1.27 1.27)
				)
			)
		)
		(property "Current" ""
			(at 99.06 259.08 0)
			(effects
				(font
					(size 1.27 1.27)
					(thickness 0.15)
				)
				(justify left bottom)
				(hide yes)
			)
		)
		(pin "1"
		)
		(pin "2"
		)
		(instances
			(project "k410t-devboard"
				(path ""
					(reference "FB3")
					(unit 1)
				)
			)
		)
	)
	(symbol
		(lib_id "antmicroResistors0402:R_49k9_0402")
		(at 125.73 261.62 0)
		(unit 1)
		(exclude_from_sim no)
		(in_bom yes)
		(on_board yes)
		(dnp no)
		(property "Reference" "R48"
			(at 133.35 260.35 0)
			(effects
				(font
					(size 1.27 1.27)
				)
			)
		)
		(property "Value" "R_49k9_0402"
			(at 146.05 274.32 0)
			(effects
				(font
					(size 1.27 1.27)
					(thickness 0.15)
				)
				(justify left bottom)
				(hide yes)
			)
		)
		(property "Footprint" "antmicro-footprints:R_0402_1005Metric"
			(at 146.05 276.86 0)
			(effects
				(font
					(size 1.27 1.27)
					(thickness 0.15)
				)
				(justify left bottom)
				(hide yes)
			)
		)
		(property "Datasheet" "https://www.bourns.com/docs/product-datasheets/cr.pdf"
			(at 146.05 279.4 0)
			(effects
				(font
					(size 1.27 1.27)
					(thickness 0.15)
				)
				(justify left bottom)
				(hide yes)
			)
		)
		(property "Description" ""
			(at 125.73 261.62 0)
			(effects
				(font
					(size 1.27 1.27)
				)
			)
		)
		(property "Manufacturer" "Bourns"
			(at 146.05 284.48 0)
			(effects
				(font
					(size 1.27 1.27)
					(thickness 0.15)
				)
				(justify left bottom)
				(hide yes)
			)
		)
		(property "MPN" "CR0402-FX-4992GLF"
			(at 146.05 281.94 0)
			(effects
				(font
					(size 1.27 1.27)
					(thickness 0.15)
				)
				(justify left bottom)
				(hide yes)
			)
		)
		(property "Val" "49k9"
			(at 123.19 260.35 0)
			(effects
				(font
					(size 1.27 1.27)
					(thickness 0.15)
				)
			)
		)
		(property "License" "Apache-2.0"
			(at 146.05 287.02 0)
			(effects
				(font
					(size 1.27 1.27)
					(thickness 0.15)
				)
				(justify left bottom)
				(hide yes)
			)
		)
		(property "Author" "Antmicro"
			(at 146.05 289.56 0)
			(effects
				(font
					(size 1.27 1.27)
					(thickness 0.15)
				)
				(justify left bottom)
				(hide yes)
			)
		)
		(property "Tolerance" "1%"
			(at 146.05 271.78 0)
			(effects
				(font
					(size 1.27 1.27)
				)
				(justify left bottom)
				(hide yes)
			)
		)
		(pin "1"
		)
		(pin "2"
		)
		(instances
			(project "k410t-devboard"
				(path ""
					(reference "R48")
					(unit 1)
				)
			)
		)
	)
	(symbol
		(lib_id "antmicroTransistorsFETsMOSFETsSingle:BSS138PW")
		(at 196.85 256.54 0)
		(unit 1)
		(exclude_from_sim no)
		(in_bom yes)
		(on_board yes)
		(dnp no)
		(fields_autoplaced yes)
		(property "Reference" "Q18"
			(at 208.28 252.73 0)
			(effects
				(font
					(size 1.27 1.27)
				)
				(justify left)
			)
		)
		(property "Value" "BSS138PW"
			(at 208.28 255.2699 0)
			(effects
				(font
					(size 1.27 1.27)
					(thickness 0.15)
				)
				(justify left)
				(hide yes)
			)
		)
		(property "Footprint" "antmicro-footprints:SC70-3"
			(at 219.71 267.97 0)
			(effects
				(font
					(size 1.27 1.27)
					(thickness 0.15)
				)
				(justify left bottom)
				(hide yes)
			)
		)
		(property "Datasheet" "https://assets.nexperia.com/documents/data-sheet/BSS138PW.pdf"
			(at 219.71 270.51 0)
			(effects
				(font
					(size 1.27 1.27)
					(thickness 0.15)
				)
				(justify left bottom)
				(hide yes)
			)
		)
		(property "Description" ""
			(at 196.85 256.54 0)
			(effects
				(font
					(size 1.27 1.27)
				)
			)
		)
		(property "MPN" "BSS138PW"
			(at 208.28 255.27 0)
			(effects
				(font
					(size 1.27 1.27)
					(thickness 0.15)
				)
				(justify left)
			)
		)
		(property "Manufacturer" "Nexperia"
			(at 219.71 275.59 0)
			(effects
				(font
					(size 1.27 1.27)
					(thickness 0.15)
				)
				(justify left bottom)
				(hide yes)
			)
		)
		(property "Author" "Antmicro"
			(at 219.71 278.13 0)
			(effects
				(font
					(size 1.27 1.27)
					(thickness 0.15)
				)
				(justify left bottom)
				(hide yes)
			)
		)
		(property "License" "Apache-2.0"
			(at 219.71 280.67 0)
			(effects
				(font
					(size 1.27 1.27)
					(thickness 0.15)
				)
				(justify left bottom)
				(hide yes)
			)
		)
		(pin "1"
		)
		(pin "2"
		)
		(pin "3"
		)
		(instances
			(project "k410t-devboard"
				(path ""
					(reference "Q18")
					(unit 1)
				)
			)
		)
	)
	(symbol
		(lib_id "antmicroCapacitorsmisc:C_22u_100V_2220")
		(at 151.13 198.12 90)
		(unit 1)
		(exclude_from_sim no)
		(in_bom yes)
		(on_board yes)
		(dnp no)
		(property "Reference" "C197"
			(at 151.13 193.04 90)
			(effects
				(font
					(size 1.27 1.27)
				)
				(justify right)
			)
		)
		(property "Value" "C_22u_100V_2220"
			(at 161.29 177.8 0)
			(effects
				(font
					(size 1.27 1.27)
					(thickness 0.15)
				)
				(justify left bottom)
				(hide yes)
			)
		)
		(property "Footprint" "antmicro-footprints:C_2220_5650Metric"
			(at 163.83 177.8 0)
			(effects
				(font
					(size 1.27 1.27)
					(thickness 0.15)
				)
				(justify left bottom)
				(hide yes)
			)
		)
		(property "Datasheet" "https://product.tdk.com/en/search/capacitor/ceramic/mlcc/info?part_no=C5750X7S2A226M280KB"
			(at 166.37 177.8 0)
			(effects
				(font
					(size 1.27 1.27)
					(thickness 0.15)
				)
				(justify left bottom)
				(hide yes)
			)
		)
		(property "Description" ""
			(at 151.13 198.12 0)
			(effects
				(font
					(size 1.27 1.27)
				)
			)
		)
		(property "Manufacturer" "TDK"
			(at 171.45 177.8 0)
			(effects
				(font
					(size 1.27 1.27)
					(thickness 0.15)
				)
				(justify left bottom)
				(hide yes)
			)
		)
		(property "MPN" "C5750X7S2A226M280KB"
			(at 168.91 177.8 0)
			(effects
				(font
					(size 1.27 1.27)
					(thickness 0.15)
				)
				(justify left bottom)
				(hide yes)
			)
		)
		(property "Val" "22u"
			(at 151.13 198.12 90)
			(effects
				(font
					(size 1.27 1.27)
					(thickness 0.15)
				)
				(justify right)
			)
		)
		(property "License" "Apache-2.0"
			(at 173.99 177.8 0)
			(effects
				(font
					(size 1.27 1.27)
					(thickness 0.15)
				)
				(justify left bottom)
				(hide yes)
			)
		)
		(property "Author" "Antmicro"
			(at 176.53 177.8 0)
			(effects
				(font
					(size 1.27 1.27)
					(thickness 0.15)
				)
				(justify left bottom)
				(hide yes)
			)
		)
		(property "Voltage" "100V"
			(at 151.13 200.66 90)
			(effects
				(font
					(size 1.27 1.27)
				)
				(justify right)
			)
		)
		(property "Dielectric" "X7S"
			(at 181.61 177.8 0)
			(effects
				(font
					(size 1.27 1.27)
				)
				(justify left bottom)
				(hide yes)
			)
		)
		(pin "1"
		)
		(pin "2"
		)
		(instances
			(project "k410t-devboard"
				(path ""
					(reference "C197")
					(unit 1)
				)
			)
		)
	)
	(symbol
		(lib_id "antmicroResistors0402:R_100k_0402")
		(at 128.905 91.44 90)
		(unit 1)
		(exclude_from_sim no)
		(in_bom yes)
		(on_board yes)
		(dnp no)
		(fields_autoplaced yes)
		(property "Reference" "R50"
			(at 131.445 87.6299 90)
			(effects
				(font
					(size 1.27 1.27)
				)
				(justify right)
			)
		)
		(property "Value" "R_100k_0402"
			(at 141.605 71.12 0)
			(effects
				(font
					(size 1.27 1.27)
					(thickness 0.15)
				)
				(justify left bottom)
				(hide yes)
			)
		)
		(property "Footprint" "antmicro-footprints:R_0402_1005Metric"
			(at 144.145 71.12 0)
			(effects
				(font
					(size 1.27 1.27)
					(thickness 0.15)
				)
				(justify left bottom)
				(hide yes)
			)
		)
		(property "Datasheet" "https://www.bourns.com/docs/product-datasheets/cr.pdf"
			(at 146.685 71.12 0)
			(effects
				(font
					(size 1.27 1.27)
					(thickness 0.15)
				)
				(justify left bottom)
				(hide yes)
			)
		)
		(property "Description" ""
			(at 128.905 91.44 0)
			(effects
				(font
					(size 1.27 1.27)
				)
			)
		)
		(property "Manufacturer" "Bourns"
			(at 151.765 71.12 0)
			(effects
				(font
					(size 1.27 1.27)
					(thickness 0.15)
				)
				(justify left bottom)
				(hide yes)
			)
		)
		(property "MPN" "CR0402-FX-1003GLF"
			(at 149.225 71.12 0)
			(effects
				(font
					(size 1.27 1.27)
					(thickness 0.15)
				)
				(justify left bottom)
				(hide yes)
			)
		)
		(property "Val" "100k"
			(at 131.445 90.1699 90)
			(effects
				(font
					(size 1.27 1.27)
					(thickness 0.15)
				)
				(justify right)
			)
		)
		(property "License" "Apache-2.0"
			(at 154.305 71.12 0)
			(effects
				(font
					(size 1.27 1.27)
					(thickness 0.15)
				)
				(justify left bottom)
				(hide yes)
			)
		)
		(property "Author" "Antmicro"
			(at 156.845 71.12 0)
			(effects
				(font
					(size 1.27 1.27)
					(thickness 0.15)
				)
				(justify left bottom)
				(hide yes)
			)
		)
		(property "Tolerance" "1%"
			(at 139.065 71.12 0)
			(effects
				(font
					(size 1.27 1.27)
				)
				(justify left bottom)
				(hide yes)
			)
		)
		(pin "1"
		)
		(pin "2"
		)
		(instances
			(project "k410t-devboard"
				(path ""
					(reference "R50")
					(unit 1)
				)
			)
		)
	)
	(symbol
		(lib_id "antmicropower:GNDD")
		(at 151.13 208.28 0)
		(unit 1)
		(exclude_from_sim no)
		(in_bom yes)
		(on_board yes)
		(dnp no)
		(property "Reference" "#PWR097"
			(at 151.13 214.63 0)
			(effects
				(font
					(size 1.27 1.27)
				)
				(hide yes)
			)
		)
		(property "Value" "GNDD"
			(at 151.13 212.09 0)
			(effects
				(font
					(size 1.27 1.27)
				)
			)
		)
		(property "Footprint" ""
			(at 151.13 208.28 0)
			(effects
				(font
					(size 1.27 1.27)
				)
				(hide yes)
			)
		)
		(property "Datasheet" ""
			(at 151.13 208.28 0)
			(effects
				(font
					(size 1.27 1.27)
				)
				(hide yes)
			)
		)
		(property "Description" ""
			(at 151.13 208.28 0)
			(effects
				(font
					(size 1.27 1.27)
				)
			)
		)
		(property "Author" "Antmicro"
			(at 166.37 215.9 0)
			(effects
				(font
					(size 1.27 1.27)
					(thickness 0.15)
				)
				(justify left bottom)
				(hide yes)
			)
		)
		(property "License" "Apache-2.0"
			(at 166.37 218.44 0)
			(effects
				(font
					(size 1.27 1.27)
					(thickness 0.15)
				)
				(justify left bottom)
				(hide yes)
			)
		)
		(pin "1"
		)
		(instances
			(project "k410t-devboard"
				(path ""
					(reference "#PWR097")
					(unit 1)
				)
			)
		)
	)
	(symbol
		(lib_id "antmicroPMICORControllersIdealDiodes:LTC4412IS6")
		(at 314.96 44.45 0)
		(unit 1)
		(exclude_from_sim no)
		(in_bom yes)
		(on_board yes)
		(dnp no)
		(fields_autoplaced yes)
		(property "Reference" "U9"
			(at 323.85 36.83 0)
			(effects
				(font
					(size 1.27 1.27)
				)
			)
		)
		(property "Value" "LTC4412IS6"
			(at 323.85 40.64 0)
			(effects
				(font
					(size 1.27 1.27)
					(thickness 0.15)
				)
				(hide yes)
			)
		)
		(property "Footprint" "antmicro-footprints:SOT-23-6"
			(at 346.71 52.07 0)
			(effects
				(font
					(size 1.27 1.27)
					(thickness 0.15)
				)
				(justify left bottom)
				(hide yes)
			)
		)
		(property "Datasheet" "https://www.mouser.com/datasheet/2/308/NCV8187_D-1813214.pdf"
			(at 346.71 54.61 0)
			(effects
				(font
					(size 1.27 1.27)
					(thickness 0.15)
				)
				(justify left bottom)
				(hide yes)
			)
		)
		(property "Description" ""
			(at 314.96 44.45 0)
			(effects
				(font
					(size 1.27 1.27)
				)
			)
		)
		(property "MPN" "LTC4412IS6#TRMPBF"
			(at 323.85 39.37 0)
			(effects
				(font
					(size 1.27 1.27)
					(thickness 0.15)
				)
			)
		)
		(property "Manufacturer" "Analog Devices"
			(at 346.71 59.69 0)
			(effects
				(font
					(size 1.27 1.27)
					(thickness 0.15)
				)
				(justify left bottom)
				(hide yes)
			)
		)
		(property "Author" "Antmicro"
			(at 346.71 62.23 0)
			(effects
				(font
					(size 1.27 1.27)
					(thickness 0.15)
				)
				(justify left bottom)
				(hide yes)
			)
		)
		(property "License" "Apache-2.0"
			(at 346.71 64.77 0)
			(effects
				(font
					(size 1.27 1.27)
					(thickness 0.15)
				)
				(justify left bottom)
				(hide yes)
			)
		)
		(pin "1"
		)
		(pin "2"
		)
		(pin "3"
		)
		(pin "4"
		)
		(pin "5"
		)
		(pin "6"
		)
		(instances
			(project "k410t-devboard"
				(path ""
					(reference "U9")
					(unit 1)
				)
			)
		)
	)
	(symbol
		(lib_id "antmicropower:GND")
		(at 313.69 105.41 0)
		(unit 1)
		(exclude_from_sim no)
		(in_bom yes)
		(on_board yes)
		(dnp no)
		(fields_autoplaced yes)
		(property "Reference" "#PWR0110"
			(at 313.69 111.76 0)
			(effects
				(font
					(size 1.27 1.27)
				)
				(hide yes)
			)
		)
		(property "Value" "GND"
			(at 313.69 109.22 0)
			(effects
				(font
					(size 1.27 1.27)
				)
			)
		)
		(property "Footprint" ""
			(at 322.58 113.03 0)
			(effects
				(font
					(size 1.27 1.27)
					(thickness 0.15)
				)
				(justify left bottom)
				(hide yes)
			)
		)
		(property "Datasheet" ""
			(at 322.58 118.11 0)
			(effects
				(font
					(size 1.27 1.27)
					(thickness 0.15)
				)
				(justify left bottom)
				(hide yes)
			)
		)
		(property "Description" ""
			(at 313.69 105.41 0)
			(effects
				(font
					(size 1.27 1.27)
				)
			)
		)
		(property "Author" "Antmicro"
			(at 322.58 113.03 0)
			(effects
				(font
					(size 1.27 1.27)
					(thickness 0.15)
				)
				(justify left bottom)
				(hide yes)
			)
		)
		(property "License" "Apache-2.0"
			(at 322.58 115.57 0)
			(effects
				(font
					(size 1.27 1.27)
					(thickness 0.15)
				)
				(justify left bottom)
				(hide yes)
			)
		)
		(pin "1"
		)
		(instances
			(project "k410t-devboard"
				(path ""
					(reference "#PWR0110")
					(unit 1)
				)
			)
		)
	)
	(symbol
		(lib_id "antmicropower:GND")
		(at 172.72 104.14 0)
		(unit 1)
		(exclude_from_sim no)
		(in_bom yes)
		(on_board yes)
		(dnp no)
		(property "Reference" "#PWR0102"
			(at 172.72 110.49 0)
			(effects
				(font
					(size 1.27 1.27)
				)
				(hide yes)
			)
		)
		(property "Value" "GND"
			(at 172.72 107.95 0)
			(effects
				(font
					(size 1.27 1.27)
				)
			)
		)
		(property "Footprint" ""
			(at 181.61 111.76 0)
			(effects
				(font
					(size 1.27 1.27)
					(thickness 0.15)
				)
				(justify left bottom)
				(hide yes)
			)
		)
		(property "Datasheet" ""
			(at 181.61 116.84 0)
			(effects
				(font
					(size 1.27 1.27)
					(thickness 0.15)
				)
				(justify left bottom)
				(hide yes)
			)
		)
		(property "Description" ""
			(at 172.72 104.14 0)
			(effects
				(font
					(size 1.27 1.27)
				)
			)
		)
		(property "Author" "Antmicro"
			(at 181.61 111.76 0)
			(effects
				(font
					(size 1.27 1.27)
					(thickness 0.15)
				)
				(justify left bottom)
				(hide yes)
			)
		)
		(property "License" "Apache-2.0"
			(at 181.61 114.3 0)
			(effects
				(font
					(size 1.27 1.27)
					(thickness 0.15)
				)
				(justify left bottom)
				(hide yes)
			)
		)
		(pin "1"
		)
		(instances
			(project "k410t-devboard"
				(path ""
					(reference "#PWR0102")
					(unit 1)
				)
			)
		)
	)
	(symbol
		(lib_id "antmicroTransistorsFETsMOSFETsSingle:SI7613DN-T1-GE3")
		(at 139.065 91.44 270)
		(mirror x)
		(unit 1)
		(exclude_from_sim no)
		(in_bom yes)
		(on_board yes)
		(dnp no)
		(fields_autoplaced yes)
		(property "Reference" "Q4"
			(at 141.605 76.2 90)
			(effects
				(font
					(size 1.27 1.27)
				)
			)
		)
		(property "Value" "SI7613DN-T1-GE3"
			(at 141.605 78.74 90)
			(effects
				(font
					(size 1.27 1.27)
					(thickness 0.15)
				)
			)
		)
		(property "Footprint" "antmicro-footprints:Vishay_PowerPAK_1212-8_Single"
			(at 140.335 76.2 0)
			(effects
				(font
					(size 1.27 1.27)
					(thickness 0.15)
				)
				(justify left bottom)
				(hide yes)
			)
		)
		(property "Datasheet" "https://www.vishay.com/docs/64809/si7613dn.pdf"
			(at 137.795 76.2 0)
			(effects
				(font
					(size 1.27 1.27)
					(thickness 0.15)
				)
				(justify left bottom)
				(hide yes)
			)
		)
		(property "Description" ""
			(at 139.065 91.44 0)
			(effects
				(font
					(size 1.27 1.27)
				)
			)
		)
		(property "MPN" "SI7613DN-T1-GE3"
			(at 133.985 76.2 0)
			(effects
				(font
					(size 1.27 1.27)
					(thickness 0.15)
				)
				(justify left bottom)
				(hide yes)
			)
		)
		(property "Manufacturer" "Vishay"
			(at 131.445 76.2 0)
			(effects
				(font
					(size 1.27 1.27)
					(thickness 0.15)
				)
				(justify left bottom)
				(hide yes)
			)
		)
		(property "Author" "Antmicro"
			(at 128.905 76.2 0)
			(effects
				(font
					(size 1.27 1.27)
					(thickness 0.15)
				)
				(justify left bottom)
				(hide yes)
			)
		)
		(property "License" "Apache-2.0"
			(at 126.365 76.2 0)
			(effects
				(font
					(size 1.27 1.27)
					(thickness 0.15)
				)
				(justify left bottom)
				(hide yes)
			)
		)
		(pin "1"
		)
		(pin "2"
		)
		(pin "3"
		)
		(pin "4"
		)
		(pin "5"
		)
		(instances
			(project "k410t-devboard"
				(path ""
					(reference "Q4")
					(unit 1)
				)
			)
		)
	)
	(symbol
		(lib_id "antmicroDiodesRectifiersSingle:PMEG3050EP,115")
		(at 332.74 21.59 0)
		(unit 1)
		(exclude_from_sim no)
		(in_bom no)
		(on_board yes)
		(dnp yes)
		(property "Reference" "D15"
			(at 335.5975 14.605 0)
			(effects
				(font
					(size 1.27 1.27)
				)
			)
		)
		(property "Value" "PMEG3050EP,115"
			(at 335.5975 17.145 0)
			(effects
				(font
					(size 1.27 1.27)
					(thickness 0.15)
				)
			)
		)
		(property "Footprint" "antmicro-footprints:Nexperia_SOD128"
			(at 354.33 31.75 0)
			(effects
				(font
					(size 1.27 1.27)
					(thickness 0.15)
				)
				(justify left bottom)
				(hide yes)
			)
		)
		(property "Datasheet" "https://www.mouser.com/datasheet/2/916/PMEG3050EP-2938519.pdf"
			(at 354.33 34.29 0)
			(effects
				(font
					(size 1.27 1.27)
					(thickness 0.15)
				)
				(justify left bottom)
				(hide yes)
			)
		)
		(property "Description" ""
			(at 332.74 21.59 0)
			(effects
				(font
					(size 1.27 1.27)
				)
			)
		)
		(property "MPN" "PMEG3050EP,115"
			(at 354.33 36.83 0)
			(effects
				(font
					(size 1.27 1.27)
					(thickness 0.15)
				)
				(justify left bottom)
				(hide yes)
			)
		)
		(property "Manufacturer" "Nexperia"
			(at 354.33 39.37 0)
			(effects
				(font
					(size 1.27 1.27)
					(thickness 0.15)
				)
				(justify left bottom)
				(hide yes)
			)
		)
		(property "Author" "Antmicro"
			(at 354.33 41.91 0)
			(effects
				(font
					(size 1.27 1.27)
					(thickness 0.15)
				)
				(justify left bottom)
				(hide yes)
			)
		)
		(property "License" "Apache-2.0"
			(at 354.33 44.45 0)
			(effects
				(font
					(size 1.27 1.27)
					(thickness 0.15)
				)
				(justify left bottom)
				(hide yes)
			)
		)
		(property "DNP" "DNP"
			(at 339.09 22.86 0)
			(effects
				(font
					(size 1.27 1.27)
				)
			)
		)
		(pin "1"
		)
		(pin "2"
		)
		(instances
			(project "k410t-devboard"
				(path ""
					(reference "D15")
					(unit 1)
				)
			)
		)
	)
	(symbol
		(lib_id "antmicroCapacitors0603:C_1u_25V_0603")
		(at 350.52 101.6 90)
		(unit 1)
		(exclude_from_sim no)
		(in_bom yes)
		(on_board yes)
		(dnp no)
		(fields_autoplaced yes)
		(property "Reference" "C207"
			(at 353.695 97.7835 90)
			(effects
				(font
					(size 1.27 1.27)
				)
				(justify right)
			)
		)
		(property "Value" "C_1u_25V_0603"
			(at 360.68 81.28 0)
			(effects
				(font
					(size 1.27 1.27)
					(thickness 0.15)
				)
				(justify left bottom)
				(hide yes)
			)
		)
		(property "Footprint" "antmicro-footprints:C_0603_1608Metric"
			(at 363.22 81.28 0)
			(effects
				(font
					(size 1.27 1.27)
					(thickness 0.15)
				)
				(justify left bottom)
				(hide yes)
			)
		)
		(property "Datasheet" "https://product.samsungsem.com/mlcc/CL10A105KA8NNN.do"
			(at 365.76 81.28 0)
			(effects
				(font
					(size 1.27 1.27)
					(thickness 0.15)
				)
				(justify left bottom)
				(hide yes)
			)
		)
		(property "Description" ""
			(at 350.52 101.6 0)
			(effects
				(font
					(size 1.27 1.27)
				)
			)
		)
		(property "Manufacturer" "Samsung Electro-Mechanics"
			(at 370.84 81.28 0)
			(effects
				(font
					(size 1.27 1.27)
					(thickness 0.15)
				)
				(justify left bottom)
				(hide yes)
			)
		)
		(property "MPN" "CL10A105KA8NNNC"
			(at 368.3 81.28 0)
			(effects
				(font
					(size 1.27 1.27)
					(thickness 0.15)
				)
				(justify left bottom)
				(hide yes)
			)
		)
		(property "Val" "1u"
			(at 353.695 100.3235 90)
			(effects
				(font
					(size 1.27 1.27)
					(thickness 0.15)
				)
				(justify right)
			)
		)
		(property "License" "Apache-2.0"
			(at 373.38 81.28 0)
			(effects
				(font
					(size 1.27 1.27)
					(thickness 0.15)
				)
				(justify left bottom)
				(hide yes)
			)
		)
		(property "Author" "Antmicro"
			(at 375.92 81.28 0)
			(effects
				(font
					(size 1.27 1.27)
					(thickness 0.15)
				)
				(justify left bottom)
				(hide yes)
			)
		)
		(property "Voltage" "25V"
			(at 378.46 81.28 0)
			(effects
				(font
					(size 1.27 1.27)
				)
				(justify left bottom)
				(hide yes)
			)
		)
		(property "Dielectric" ""
			(at 381 81.28 0)
			(effects
				(font
					(size 1.27 1.27)
				)
				(justify left bottom)
				(hide yes)
			)
		)
		(pin "1"
		)
		(pin "2"
		)
		(instances
			(project "k410t-devboard"
				(path ""
					(reference "C207")
					(unit 1)
				)
			)
		)
	)
	(symbol
		(lib_id "antmicroCapacitors0402:C_100n_0402")
		(at 303.53 52.07 90)
		(unit 1)
		(exclude_from_sim no)
		(in_bom yes)
		(on_board yes)
		(dnp no)
		(fields_autoplaced yes)
		(property "Reference" "C203"
			(at 306.07 48.2535 90)
			(effects
				(font
					(size 1.27 1.27)
				)
				(justify right)
			)
		)
		(property "Value" "C_100n_0402"
			(at 313.69 31.75 0)
			(effects
				(font
					(size 1.27 1.27)
					(thickness 0.15)
				)
				(justify left bottom)
				(hide yes)
			)
		)
		(property "Footprint" "antmicro-footprints:C_0402_1005Metric"
			(at 316.23 31.75 0)
			(effects
				(font
					(size 1.27 1.27)
					(thickness 0.15)
				)
				(justify left bottom)
				(hide yes)
			)
		)
		(property "Datasheet" "https://www.murata.com/products/productdetail?partno=GRM155R61H104KE14%23"
			(at 318.77 31.75 0)
			(effects
				(font
					(size 1.27 1.27)
					(thickness 0.15)
				)
				(justify left bottom)
				(hide yes)
			)
		)
		(property "Description" ""
			(at 303.53 52.07 0)
			(effects
				(font
					(size 1.27 1.27)
				)
			)
		)
		(property "Manufacturer" "Murata"
			(at 323.85 31.75 0)
			(effects
				(font
					(size 1.27 1.27)
					(thickness 0.15)
				)
				(justify left bottom)
				(hide yes)
			)
		)
		(property "MPN" "GRM155R61H104KE14D"
			(at 321.31 31.75 0)
			(effects
				(font
					(size 1.27 1.27)
					(thickness 0.15)
				)
				(justify left bottom)
				(hide yes)
			)
		)
		(property "Val" "100n"
			(at 306.07 50.7935 90)
			(effects
				(font
					(size 1.27 1.27)
					(thickness 0.15)
				)
				(justify right)
			)
		)
		(property "License" "Apache-2.0"
			(at 326.39 31.75 0)
			(effects
				(font
					(size 1.27 1.27)
					(thickness 0.15)
				)
				(justify left bottom)
				(hide yes)
			)
		)
		(property "Author" "Antmicro"
			(at 328.93 31.75 0)
			(effects
				(font
					(size 1.27 1.27)
					(thickness 0.15)
				)
				(justify left bottom)
				(hide yes)
			)
		)
		(property "Voltage" "50V"
			(at 331.47 31.75 0)
			(effects
				(font
					(size 1.27 1.27)
				)
				(justify left bottom)
				(hide yes)
			)
		)
		(property "Dielectric" "X5R"
			(at 334.01 31.75 0)
			(effects
				(font
					(size 1.27 1.27)
				)
				(justify left bottom)
				(hide yes)
			)
		)
		(pin "1"
		)
		(pin "2"
		)
		(instances
			(project "k410t-devboard"
				(path ""
					(reference "C203")
					(unit 1)
				)
			)
		)
	)
	(symbol
		(lib_id "antmicroLEDIndicationDiscrete:LED_R_0603_KP-1608EC")
		(at 115.57 207.01 270)
		(mirror x)
		(unit 1)
		(exclude_from_sim no)
		(in_bom yes)
		(on_board yes)
		(dnp no)
		(property "Reference" "D9"
			(at 119.38 204.47 90)
			(effects
				(font
					(size 1.27 1.27)
				)
				(justify left)
			)
		)
		(property "Value" "LED_R_0603_KP-1608EC"
			(at 118.745 201.9301 90)
			(effects
				(font
					(size 1.27 1.27)
					(thickness 0.15)
				)
				(justify left)
				(hide yes)
			)
		)
		(property "Footprint" "antmicro-footprints:LED_0603_1608Metric_R"
			(at 105.41 184.15 0)
			(effects
				(font
					(size 1.27 1.27)
					(thickness 0.15)
				)
				(justify left bottom)
				(hide yes)
			)
		)
		(property "Datasheet" "http://www.kingbright.com/attachments/file/psearch/000/00/20131112/KP-1608EC(Ver.14A).pdf"
			(at 102.87 184.15 0)
			(effects
				(font
					(size 1.27 1.27)
					(thickness 0.15)
				)
				(justify left bottom)
				(hide yes)
			)
		)
		(property "Description" ""
			(at 115.57 207.01 0)
			(effects
				(font
					(size 1.27 1.27)
				)
			)
		)
		(property "MPN" "KP-1608EC"
			(at 100.33 184.15 0)
			(effects
				(font
					(size 1.27 1.27)
					(thickness 0.15)
				)
				(justify left bottom)
				(hide yes)
			)
		)
		(property "Manufacturer" "Kingbright"
			(at 97.79 184.15 0)
			(effects
				(font
					(size 1.27 1.27)
					(thickness 0.15)
				)
				(justify left bottom)
				(hide yes)
			)
		)
		(property "Author" "Antmicro"
			(at 95.25 184.15 0)
			(effects
				(font
					(size 1.27 1.27)
					(thickness 0.15)
				)
				(justify left bottom)
				(hide yes)
			)
		)
		(property "License" "Apache-2.0"
			(at 92.71 184.15 0)
			(effects
				(font
					(size 1.27 1.27)
					(thickness 0.15)
				)
				(justify left bottom)
				(hide yes)
			)
		)
		(property "Color" "Red"
			(at 119.38 201.93 90)
			(effects
				(font
					(size 1.27 1.27)
				)
				(justify left)
			)
		)
		(property "Public" "False"
			(at 97.79 186.69 0)
			(effects
				(font
					(size 1.27 1.27)
				)
				(justify left bottom)
				(hide yes)
			)
		)
		(pin "1"
		)
		(pin "2"
		)
		(instances
			(project "k410t-devboard"
				(path ""
					(reference "D9")
					(unit 1)
				)
			)
		)
	)
	(symbol
		(lib_id "antmicropower:GND")
		(at 181.61 153.67 0)
		(mirror y)
		(unit 1)
		(exclude_from_sim no)
		(in_bom yes)
		(on_board yes)
		(dnp no)
		(property "Reference" "#PWR0105"
			(at 181.61 160.02 0)
			(effects
				(font
					(size 1.27 1.27)
				)
				(hide yes)
			)
		)
		(property "Value" "GND"
			(at 181.61 157.48 0)
			(effects
				(font
					(size 1.27 1.27)
				)
			)
		)
		(property "Footprint" ""
			(at 172.72 161.29 0)
			(effects
				(font
					(size 1.27 1.27)
					(thickness 0.15)
				)
				(justify left bottom)
				(hide yes)
			)
		)
		(property "Datasheet" ""
			(at 172.72 166.37 0)
			(effects
				(font
					(size 1.27 1.27)
					(thickness 0.15)
				)
				(justify left bottom)
				(hide yes)
			)
		)
		(property "Description" ""
			(at 181.61 153.67 0)
			(effects
				(font
					(size 1.27 1.27)
				)
			)
		)
		(property "Author" "Antmicro"
			(at 172.72 161.29 0)
			(effects
				(font
					(size 1.27 1.27)
					(thickness 0.15)
				)
				(justify left bottom)
				(hide yes)
			)
		)
		(property "License" "Apache-2.0"
			(at 172.72 163.83 0)
			(effects
				(font
					(size 1.27 1.27)
					(thickness 0.15)
				)
				(justify left bottom)
				(hide yes)
			)
		)
		(pin "1"
		)
		(instances
			(project "k410t-devboard"
				(path ""
					(reference "#PWR0105")
					(unit 1)
				)
			)
		)
	)
	(symbol
		(lib_id "antmicroFerriteBeadsandChips:FB_220Z_2A_Murata-BLM21PG_0805")
		(at 78.74 190.5 0)
		(unit 1)
		(exclude_from_sim no)
		(in_bom yes)
		(on_board yes)
		(dnp no)
		(fields_autoplaced yes)
		(property "Reference" "FB1"
			(at 81.2419 184.15 0)
			(effects
				(font
					(size 1.27 1.27)
				)
			)
		)
		(property "Value" "FB_220Z_2A_Murata-BLM21PG_0805"
			(at 81.2419 186.69 0)
			(effects
				(font
					(size 1.27 1.27)
					(thickness 0.15)
				)
				(hide yes)
			)
		)
		(property "Footprint" "antmicro-footprints:FB_0805_2012Metric"
			(at 92.71 195.58 0)
			(effects
				(font
					(size 1.27 1.27)
					(thickness 0.15)
				)
				(justify left bottom)
				(hide yes)
			)
		)
		(property "Datasheet" "https://www.murata.com/products/productdata/8796738977822/ENFA0005.pdf?1653276712000"
			(at 92.71 198.12 0)
			(effects
				(font
					(size 1.27 1.27)
					(thickness 0.15)
				)
				(justify left bottom)
				(hide yes)
			)
		)
		(property "Description" ""
			(at 78.74 190.5 0)
			(effects
				(font
					(size 1.27 1.27)
				)
			)
		)
		(property "MPN" "BLM21PG221SN1D"
			(at 92.71 200.66 0)
			(effects
				(font
					(size 1.27 1.27)
					(thickness 0.15)
				)
				(justify left bottom)
				(hide yes)
			)
		)
		(property "Manufacturer" "Murata"
			(at 92.71 203.2 0)
			(effects
				(font
					(size 1.27 1.27)
					(thickness 0.15)
				)
				(justify left bottom)
				(hide yes)
			)
		)
		(property "Author" "Antmicro"
			(at 92.71 205.74 0)
			(effects
				(font
					(size 1.27 1.27)
					(thickness 0.15)
				)
				(justify left bottom)
				(hide yes)
			)
		)
		(property "License" "Apache-2.0"
			(at 92.71 208.28 0)
			(effects
				(font
					(size 1.27 1.27)
					(thickness 0.15)
				)
				(justify left bottom)
				(hide yes)
			)
		)
		(property "Val" "220Z/2A"
			(at 81.2419 186.69 0)
			(effects
				(font
					(size 1.27 1.27)
				)
			)
		)
		(property "Current" ""
			(at 99.06 213.36 0)
			(effects
				(font
					(size 1.27 1.27)
					(thickness 0.15)
				)
				(justify left bottom)
				(hide yes)
			)
		)
		(pin "1"
		)
		(pin "2"
		)
		(instances
			(project "k410t-devboard"
				(path ""
					(reference "FB1")
					(unit 1)
				)
			)
		)
	)
	(symbol
		(lib_id "antmicroResistors0402:R_1k2_0402")
		(at 144.78 254 90)
		(unit 1)
		(exclude_from_sim no)
		(in_bom yes)
		(on_board yes)
		(dnp no)
		(fields_autoplaced yes)
		(property "Reference" "R53"
			(at 147.32 250.1899 90)
			(effects
				(font
					(size 1.27 1.27)
				)
				(justify right)
			)
		)
		(property "Value" "R_1k2_0402"
			(at 157.48 233.68 0)
			(effects
				(font
					(size 1.27 1.27)
					(thickness 0.15)
				)
				(justify left bottom)
				(hide yes)
			)
		)
		(property "Footprint" "antmicro-footprints:R_0402_1005Metric"
			(at 160.02 233.68 0)
			(effects
				(font
					(size 1.27 1.27)
					(thickness 0.15)
				)
				(justify left bottom)
				(hide yes)
			)
		)
		(property "Datasheet" "https://www.bourns.com/docs/product-datasheets/cr.pdf"
			(at 162.56 233.68 0)
			(effects
				(font
					(size 1.27 1.27)
					(thickness 0.15)
				)
				(justify left bottom)
				(hide yes)
			)
		)
		(property "Description" ""
			(at 144.78 254 0)
			(effects
				(font
					(size 1.27 1.27)
				)
			)
		)
		(property "Manufacturer" "Bourns"
			(at 167.64 233.68 0)
			(effects
				(font
					(size 1.27 1.27)
					(thickness 0.15)
				)
				(justify left bottom)
				(hide yes)
			)
		)
		(property "MPN" "CR0402-FX-1201GLF"
			(at 165.1 233.68 0)
			(effects
				(font
					(size 1.27 1.27)
					(thickness 0.15)
				)
				(justify left bottom)
				(hide yes)
			)
		)
		(property "Val" "1k2"
			(at 147.32 252.7299 90)
			(effects
				(font
					(size 1.27 1.27)
					(thickness 0.15)
				)
				(justify right)
			)
		)
		(property "License" "Apache-2.0"
			(at 170.18 233.68 0)
			(effects
				(font
					(size 1.27 1.27)
					(thickness 0.15)
				)
				(justify left bottom)
				(hide yes)
			)
		)
		(property "Author" "Antmicro"
			(at 172.72 233.68 0)
			(effects
				(font
					(size 1.27 1.27)
					(thickness 0.15)
				)
				(justify left bottom)
				(hide yes)
			)
		)
		(property "Tolerance" "1%"
			(at 154.94 233.68 0)
			(effects
				(font
					(size 1.27 1.27)
				)
				(justify left bottom)
				(hide yes)
			)
		)
		(pin "1"
		)
		(pin "2"
		)
		(instances
			(project "k410t-devboard"
				(path ""
					(reference "R53")
					(unit 1)
				)
			)
		)
	)
	(symbol
		(lib_id "antmicroPMICPowerDistributionSwitchesLoadDrivers:TPS2372-3RGWR")
		(at 153.67 236.22 0)
		(unit 1)
		(exclude_from_sim no)
		(in_bom yes)
		(on_board yes)
		(dnp no)
		(fields_autoplaced yes)
		(property "Reference" "U7"
			(at 164.465 228.6 0)
			(effects
				(font
					(size 1.27 1.27)
				)
			)
		)
		(property "Value" "TPS2372-3RGWR"
			(at 164.465 230.505 0)
			(effects
				(font
					(size 1.27 1.27)
					(thickness 0.15)
				)
				(hide yes)
			)
		)
		(property "Footprint" "antmicro-footprints:VQFN-20_5x5x1mm_P0.65mm"
			(at 189.23 241.3 0)
			(effects
				(font
					(size 1.27 1.27)
					(thickness 0.15)
				)
				(justify left bottom)
				(hide yes)
			)
		)
		(property "Datasheet" "https://www.ti.com/lit/ds/symlink/tps2372.pdf?ts=1679042478513&ref_url=https%253A%252F%252Fwww.google.com%252F"
			(at 189.23 243.84 0)
			(effects
				(font
					(size 1.27 1.27)
					(thickness 0.15)
				)
				(justify left bottom)
				(hide yes)
			)
		)
		(property "Description" ""
			(at 153.67 236.22 0)
			(effects
				(font
					(size 1.27 1.27)
				)
			)
		)
		(property "MPN" "TPS2372-3RGWR"
			(at 164.465 231.14 0)
			(effects
				(font
					(size 1.27 1.27)
					(thickness 0.15)
				)
			)
		)
		(property "Manufacturer" "Texas Instruments"
			(at 189.23 248.92 0)
			(effects
				(font
					(size 1.27 1.27)
					(thickness 0.15)
				)
				(justify left bottom)
				(hide yes)
			)
		)
		(property "Author" "Antmicro"
			(at 189.23 251.46 0)
			(effects
				(font
					(size 1.27 1.27)
					(thickness 0.15)
				)
				(justify left bottom)
				(hide yes)
			)
		)
		(property "License" "Apache-2.0"
			(at 189.23 254 0)
			(effects
				(font
					(size 1.27 1.27)
					(thickness 0.15)
				)
				(justify left bottom)
				(hide yes)
			)
		)
		(pin "1"
		)
		(pin "10"
		)
		(pin "11"
		)
		(pin "12"
		)
		(pin "13"
		)
		(pin "14"
		)
		(pin "15"
		)
		(pin "16"
		)
		(pin "17"
		)
		(pin "18"
		)
		(pin "19"
		)
		(pin "2"
		)
		(pin "20"
		)
		(pin "21"
		)
		(pin "3"
		)
		(pin "4"
		)
		(pin "5"
		)
		(pin "6"
		)
		(pin "7"
		)
		(pin "8"
		)
		(pin "9"
		)
		(instances
			(project "k410t-devboard"
				(path ""
					(reference "U7")
					(unit 1)
				)
			)
		)
	)
	(symbol
		(lib_id "antmicroFerriteBeadsandChips:FB_220Z_2A_Murata-BLM21PG_0805")
		(at 78.74 219.71 0)
		(unit 1)
		(exclude_from_sim no)
		(in_bom yes)
		(on_board yes)
		(dnp no)
		(fields_autoplaced yes)
		(property "Reference" "FB2"
			(at 81.2419 213.36 0)
			(effects
				(font
					(size 1.27 1.27)
				)
			)
		)
		(property "Value" "FB_220Z_2A_Murata-BLM21PG_0805"
			(at 81.2419 215.265 0)
			(effects
				(font
					(size 1.27 1.27)
					(thickness 0.15)
				)
				(hide yes)
			)
		)
		(property "Footprint" "antmicro-footprints:FB_0805_2012Metric"
			(at 92.71 224.79 0)
			(effects
				(font
					(size 1.27 1.27)
					(thickness 0.15)
				)
				(justify left bottom)
				(hide yes)
			)
		)
		(property "Datasheet" "https://www.murata.com/products/productdata/8796738977822/ENFA0005.pdf?1653276712000"
			(at 92.71 227.33 0)
			(effects
				(font
					(size 1.27 1.27)
					(thickness 0.15)
				)
				(justify left bottom)
				(hide yes)
			)
		)
		(property "Description" ""
			(at 78.74 219.71 0)
			(effects
				(font
					(size 1.27 1.27)
				)
			)
		)
		(property "MPN" "BLM21PG221SN1D"
			(at 92.71 229.87 0)
			(effects
				(font
					(size 1.27 1.27)
					(thickness 0.15)
				)
				(justify left bottom)
				(hide yes)
			)
		)
		(property "Manufacturer" "Murata"
			(at 92.71 232.41 0)
			(effects
				(font
					(size 1.27 1.27)
					(thickness 0.15)
				)
				(justify left bottom)
				(hide yes)
			)
		)
		(property "Author" "Antmicro"
			(at 92.71 234.95 0)
			(effects
				(font
					(size 1.27 1.27)
					(thickness 0.15)
				)
				(justify left bottom)
				(hide yes)
			)
		)
		(property "License" "Apache-2.0"
			(at 92.71 237.49 0)
			(effects
				(font
					(size 1.27 1.27)
					(thickness 0.15)
				)
				(justify left bottom)
				(hide yes)
			)
		)
		(property "Val" "220Z/2A"
			(at 81.2419 215.9 0)
			(effects
				(font
					(size 1.27 1.27)
				)
			)
		)
		(property "Current" ""
			(at 99.06 242.57 0)
			(effects
				(font
					(size 1.27 1.27)
					(thickness 0.15)
				)
				(justify left bottom)
				(hide yes)
			)
		)
		(pin "1"
		)
		(pin "2"
		)
		(instances
			(project "k410t-devboard"
				(path ""
					(reference "FB2")
					(unit 1)
				)
			)
		)
	)
	(symbol
		(lib_id "antmicroResistors0402:R_22k_0402")
		(at 112.395 104.14 90)
		(unit 1)
		(exclude_from_sim no)
		(in_bom yes)
		(on_board yes)
		(dnp no)
		(fields_autoplaced yes)
		(property "Reference" "R51"
			(at 114.3 100.3299 90)
			(effects
				(font
					(size 1.27 1.27)
				)
				(justify right)
			)
		)
		(property "Value" "R_22k_0402"
			(at 125.095 83.82 0)
			(effects
				(font
					(size 1.27 1.27)
					(thickness 0.15)
				)
				(justify left bottom)
				(hide yes)
			)
		)
		(property "Footprint" "antmicro-footprints:R_0402_1005Metric"
			(at 127.635 83.82 0)
			(effects
				(font
					(size 1.27 1.27)
					(thickness 0.15)
				)
				(justify left bottom)
				(hide yes)
			)
		)
		(property "Datasheet" "https://www.bourns.com/docs/product-datasheets/cr.pdf"
			(at 130.175 83.82 0)
			(effects
				(font
					(size 1.27 1.27)
					(thickness 0.15)
				)
				(justify left bottom)
				(hide yes)
			)
		)
		(property "Description" ""
			(at 112.395 104.14 0)
			(effects
				(font
					(size 1.27 1.27)
				)
			)
		)
		(property "Manufacturer" "Bourns"
			(at 135.255 83.82 0)
			(effects
				(font
					(size 1.27 1.27)
					(thickness 0.15)
				)
				(justify left bottom)
				(hide yes)
			)
		)
		(property "MPN" "CR0402-FX-2202GLF"
			(at 132.715 83.82 0)
			(effects
				(font
					(size 1.27 1.27)
					(thickness 0.15)
				)
				(justify left bottom)
				(hide yes)
			)
		)
		(property "Val" "22k"
			(at 114.3 102.8699 90)
			(effects
				(font
					(size 1.27 1.27)
					(thickness 0.15)
				)
				(justify right)
			)
		)
		(property "License" "Apache-2.0"
			(at 137.795 83.82 0)
			(effects
				(font
					(size 1.27 1.27)
					(thickness 0.15)
				)
				(justify left bottom)
				(hide yes)
			)
		)
		(property "Author" "Antmicro"
			(at 140.335 83.82 0)
			(effects
				(font
					(size 1.27 1.27)
					(thickness 0.15)
				)
				(justify left bottom)
				(hide yes)
			)
		)
		(property "Tolerance" "1%"
			(at 122.555 83.82 0)
			(effects
				(font
					(size 1.27 1.27)
				)
				(justify left bottom)
				(hide yes)
			)
		)
		(pin "1"
		)
		(pin "2"
		)
		(instances
			(project "k410t-devboard"
				(path ""
					(reference "R51")
					(unit 1)
				)
			)
		)
	)
	(symbol
		(lib_id "antmicroTransistorsFETsMOSFETsSingle:SI7613DN-T1-GE3")
		(at 112.395 91.44 90)
		(unit 1)
		(exclude_from_sim no)
		(in_bom yes)
		(on_board yes)
		(dnp no)
		(fields_autoplaced yes)
		(property "Reference" "Q3"
			(at 109.855 76.2 90)
			(effects
				(font
					(size 1.27 1.27)
				)
			)
		)
		(property "Value" "SI7613DN-T1-GE3"
			(at 109.855 78.74 90)
			(effects
				(font
					(size 1.27 1.27)
					(thickness 0.15)
				)
			)
		)
		(property "Footprint" "antmicro-footprints:Vishay_PowerPAK_1212-8_Single"
			(at 111.125 76.2 0)
			(effects
				(font
					(size 1.27 1.27)
					(thickness 0.15)
				)
				(justify left bottom)
				(hide yes)
			)
		)
		(property "Datasheet" "https://www.vishay.com/docs/64809/si7613dn.pdf"
			(at 113.665 76.2 0)
			(effects
				(font
					(size 1.27 1.27)
					(thickness 0.15)
				)
				(justify left bottom)
				(hide yes)
			)
		)
		(property "Description" ""
			(at 112.395 91.44 0)
			(effects
				(font
					(size 1.27 1.27)
				)
			)
		)
		(property "MPN" "SI7613DN-T1-GE3"
			(at 117.475 76.2 0)
			(effects
				(font
					(size 1.27 1.27)
					(thickness 0.15)
				)
				(justify left bottom)
				(hide yes)
			)
		)
		(property "Manufacturer" "Vishay"
			(at 120.015 76.2 0)
			(effects
				(font
					(size 1.27 1.27)
					(thickness 0.15)
				)
				(justify left bottom)
				(hide yes)
			)
		)
		(property "Author" "Antmicro"
			(at 122.555 76.2 0)
			(effects
				(font
					(size 1.27 1.27)
					(thickness 0.15)
				)
				(justify left bottom)
				(hide yes)
			)
		)
		(property "License" "Apache-2.0"
			(at 125.095 76.2 0)
			(effects
				(font
					(size 1.27 1.27)
					(thickness 0.15)
				)
				(justify left bottom)
				(hide yes)
			)
		)
		(pin "1"
		)
		(pin "2"
		)
		(pin "3"
		)
		(pin "4"
		)
		(pin "5"
		)
		(instances
			(project "k410t-devboard"
				(path ""
					(reference "Q3")
					(unit 1)
				)
			)
		)
	)
	(symbol
		(lib_id "antmicroResistors0603:R_63R4_0603")
		(at 142.24 254 90)
		(unit 1)
		(exclude_from_sim no)
		(in_bom yes)
		(on_board yes)
		(dnp no)
		(fields_autoplaced yes)
		(property "Reference" "R52"
			(at 139.7 250.1899 90)
			(effects
				(font
					(size 1.27 1.27)
				)
				(justify left)
			)
		)
		(property "Value" "R_63R4_0603"
			(at 154.94 233.68 0)
			(effects
				(font
					(size 1.27 1.27)
					(thickness 0.15)
				)
				(justify left bottom)
				(hide yes)
			)
		)
		(property "Footprint" "antmicro-footprints:R_0603_1608Metric"
			(at 157.48 233.68 0)
			(effects
				(font
					(size 1.27 1.27)
					(thickness 0.15)
				)
				(justify left bottom)
				(hide yes)
			)
		)
		(property "Datasheet" "https://www.bourns.com/docs/product-datasheets/cr.pdf"
			(at 160.02 233.68 0)
			(effects
				(font
					(size 1.27 1.27)
					(thickness 0.15)
				)
				(justify left bottom)
				(hide yes)
			)
		)
		(property "Description" ""
			(at 142.24 254 0)
			(effects
				(font
					(size 1.27 1.27)
				)
			)
		)
		(property "Manufacturer" "Bourns"
			(at 165.1 233.68 0)
			(effects
				(font
					(size 1.27 1.27)
					(thickness 0.15)
				)
				(justify left bottom)
				(hide yes)
			)
		)
		(property "MPN" "CR0603-FX-63R4ELF"
			(at 162.56 233.68 0)
			(effects
				(font
					(size 1.27 1.27)
					(thickness 0.15)
				)
				(justify left bottom)
				(hide yes)
			)
		)
		(property "Val" "63R4"
			(at 139.7 252.7299 90)
			(effects
				(font
					(size 1.27 1.27)
					(thickness 0.15)
				)
				(justify left)
			)
		)
		(property "License" "Apache-2.0"
			(at 167.64 233.68 0)
			(effects
				(font
					(size 1.27 1.27)
					(thickness 0.15)
				)
				(justify left bottom)
				(hide yes)
			)
		)
		(property "Author" "Antmicro"
			(at 170.18 233.68 0)
			(effects
				(font
					(size 1.27 1.27)
					(thickness 0.15)
				)
				(justify left bottom)
				(hide yes)
			)
		)
		(property "Tolerance" "1%"
			(at 152.4 233.68 0)
			(effects
				(font
					(size 1.27 1.27)
				)
				(justify left bottom)
				(hide yes)
			)
		)
		(pin "1"
		)
		(pin "2"
		)
		(instances
			(project "k410t-devboard"
				(path ""
					(reference "R52")
					(unit 1)
				)
			)
		)
	)
	(symbol
		(lib_id "antmicroLEDIndicationDiscrete:LED_B_0603_KP-1608QBC-D")
		(at 172.72 130.81 270)
		(mirror x)
		(unit 1)
		(exclude_from_sim no)
		(in_bom yes)
		(on_board yes)
		(dnp no)
		(property "Reference" "D11"
			(at 170.18 128.27 90)
			(effects
				(font
					(size 1.27 1.27)
					(thickness 0.15)
				)
				(justify right)
			)
		)
		(property "Value" "LED_B_0603_KP-1608QBC-D"
			(at 169.545 125.7301 90)
			(effects
				(font
					(size 1.27 1.27)
					(thickness 0.15)
				)
				(justify right)
				(hide yes)
			)
		)
		(property "Footprint" "antmicro-footprints:LED_0603_1608Metric_B"
			(at 162.56 107.95 0)
			(effects
				(font
					(size 1.27 1.27)
					(thickness 0.15)
				)
				(justify left bottom)
				(hide yes)
			)
		)
		(property "Datasheet" "https://www.kingbright.com/attachments/file/psearch/000/00/00/KP-1608QBC-D(Ver.24B).pdf"
			(at 160.02 107.95 0)
			(effects
				(font
					(size 1.27 1.27)
					(thickness 0.15)
				)
				(justify left bottom)
				(hide yes)
			)
		)
		(property "Description" ""
			(at 172.72 130.81 0)
			(effects
				(font
					(size 1.27 1.27)
				)
			)
		)
		(property "MPN" "KP-1608QBC-D"
			(at 157.48 107.95 0)
			(effects
				(font
					(size 1.27 1.27)
					(thickness 0.15)
				)
				(justify left bottom)
				(hide yes)
			)
		)
		(property "Manufacturer" "Kingbright"
			(at 154.94 107.95 0)
			(effects
				(font
					(size 1.27 1.27)
					(thickness 0.15)
				)
				(justify left bottom)
				(hide yes)
			)
		)
		(property "Color" "Blue"
			(at 170.18 125.73 90)
			(effects
				(font
					(size 1.27 1.27)
					(thickness 0.15)
				)
				(justify right)
			)
		)
		(property "Author" "Antmicro"
			(at 149.86 107.95 0)
			(effects
				(font
					(size 1.27 1.27)
					(thickness 0.15)
				)
				(justify left bottom)
				(hide yes)
			)
		)
		(property "License" "Apache-2.0"
			(at 147.32 107.95 0)
			(effects
				(font
					(size 1.27 1.27)
					(thickness 0.15)
				)
				(justify left bottom)
				(hide yes)
			)
		)
		(property "Public" "False"
			(at 154.94 110.49 0)
			(effects
				(font
					(size 1.27 1.27)
				)
				(justify left bottom)
				(hide yes)
			)
		)
		(pin "1"
		)
		(pin "2"
		)
		(instances
			(project "k410t-devboard"
				(path ""
					(reference "D11")
					(unit 1)
				)
			)
		)
	)
	(symbol
		(lib_id "antmicroDCDCConverters:ULS-12_8.3-D48N-C")
		(at 176.53 190.5 0)
		(unit 1)
		(exclude_from_sim no)
		(in_bom yes)
		(on_board yes)
		(dnp no)
		(fields_autoplaced yes)
		(property "Reference" "U8"
			(at 186.563 182.88 0)
			(effects
				(font
					(size 1.27 1.27)
				)
			)
		)
		(property "Value" "ULS-12_8.3-D48N-C"
			(at 186.563 185.42 0)
			(effects
				(font
					(size 1.27 1.27)
					(thickness 0.15)
				)
				(hide yes)
			)
		)
		(property "Footprint" "antmicro-footprints:ULS-12_5-D48N-C"
			(at 212.09 198.12 0)
			(effects
				(font
					(size 1.27 1.27)
					(thickness 0.15)
				)
				(justify left bottom)
				(hide yes)
			)
		)
		(property "Datasheet" "https://www.murata.com/products/productdata/8807040286750/uls.pdf?1649388617000"
			(at 212.09 200.66 0)
			(effects
				(font
					(size 1.27 1.27)
					(thickness 0.15)
				)
				(justify left bottom)
				(hide yes)
			)
		)
		(property "Description" ""
			(at 176.53 190.5 0)
			(effects
				(font
					(size 1.27 1.27)
				)
			)
		)
		(property "Manufacturer" "Murata"
			(at 212.09 203.2 0)
			(effects
				(font
					(size 1.27 1.27)
					(thickness 0.15)
				)
				(justify left bottom)
				(hide yes)
			)
		)
		(property "MPN" "ULS-12/8.3-D48N-C"
			(at 186.563 185.42 0)
			(effects
				(font
					(size 1.27 1.27)
					(thickness 0.15)
				)
			)
		)
		(property "Author" "Antmicro"
			(at 212.09 208.28 0)
			(effects
				(font
					(size 1.27 1.27)
					(thickness 0.15)
				)
				(justify left bottom)
				(hide yes)
			)
		)
		(property "License" "Apache-2.0"
			(at 212.09 210.82 0)
			(effects
				(font
					(size 1.27 1.27)
					(thickness 0.15)
				)
				(justify left bottom)
				(hide yes)
			)
		)
		(pin "1"
		)
		(pin "2"
		)
		(pin "3"
		)
		(pin "4"
		)
		(pin "5"
		)
		(pin "6"
		)
		(pin "7"
		)
		(pin "8"
		)
		(instances
			(project "k410t-devboard"
				(path ""
					(reference "U8")
					(unit 1)
				)
			)
		)
	)
	(symbol
		(lib_id "antmicroResistors0402:R_1k_0402")
		(at 179.07 118.11 270)
		(unit 1)
		(exclude_from_sim no)
		(in_bom yes)
		(on_board yes)
		(dnp no)
		(property "Reference" "R59"
			(at 180.34 119.38 90)
			(effects
				(font
					(size 1.27 1.27)
				)
				(justify left)
			)
		)
		(property "Value" "R_1k_0402"
			(at 166.37 138.43 0)
			(effects
				(font
					(size 1.27 1.27)
					(thickness 0.15)
				)
				(justify left bottom)
				(hide yes)
			)
		)
		(property "Footprint" "antmicro-footprints:R_0402_1005Metric"
			(at 163.83 138.43 0)
			(effects
				(font
					(size 1.27 1.27)
					(thickness 0.15)
				)
				(justify left bottom)
				(hide yes)
			)
		)
		(property "Datasheet" "https://www.bourns.com/docs/product-datasheets/cr.pdf"
			(at 161.29 138.43 0)
			(effects
				(font
					(size 1.27 1.27)
					(thickness 0.15)
				)
				(justify left bottom)
				(hide yes)
			)
		)
		(property "Description" ""
			(at 179.07 118.11 0)
			(effects
				(font
					(size 1.27 1.27)
				)
			)
		)
		(property "Manufacturer" "Bourns"
			(at 156.21 138.43 0)
			(effects
				(font
					(size 1.27 1.27)
					(thickness 0.15)
				)
				(justify left bottom)
				(hide yes)
			)
		)
		(property "MPN" "CR0402-FX-1001GLF"
			(at 158.75 138.43 0)
			(effects
				(font
					(size 1.27 1.27)
					(thickness 0.15)
				)
				(justify left bottom)
				(hide yes)
			)
		)
		(property "Val" "1k"
			(at 180.34 121.92 90)
			(effects
				(font
					(size 1.27 1.27)
					(thickness 0.15)
				)
				(justify left)
			)
		)
		(property "License" "Apache-2.0"
			(at 153.67 138.43 0)
			(effects
				(font
					(size 1.27 1.27)
					(thickness 0.15)
				)
				(justify left bottom)
				(hide yes)
			)
		)
		(property "Author" "Antmicro"
			(at 151.13 138.43 0)
			(effects
				(font
					(size 1.27 1.27)
					(thickness 0.15)
				)
				(justify left bottom)
				(hide yes)
			)
		)
		(property "Tolerance" "1%"
			(at 168.91 138.43 0)
			(effects
				(font
					(size 1.27 1.27)
				)
				(justify left bottom)
				(hide yes)
			)
		)
		(pin "1"
		)
		(pin "2"
		)
		(instances
			(project "k410t-devboard"
				(path ""
					(reference "R59")
					(unit 1)
				)
			)
		)
	)
	(symbol
		(lib_id "antmicropower:GND")
		(at 182.88 93.98 0)
		(unit 1)
		(exclude_from_sim no)
		(in_bom yes)
		(on_board yes)
		(dnp no)
		(property "Reference" "#PWR0106"
			(at 182.88 100.33 0)
			(effects
				(font
					(size 1.27 1.27)
				)
				(hide yes)
			)
		)
		(property "Value" "GND"
			(at 182.88 97.79 0)
			(effects
				(font
					(size 1.27 1.27)
				)
			)
		)
		(property "Footprint" ""
			(at 191.77 101.6 0)
			(effects
				(font
					(size 1.27 1.27)
					(thickness 0.15)
				)
				(justify left bottom)
				(hide yes)
			)
		)
		(property "Datasheet" ""
			(at 191.77 106.68 0)
			(effects
				(font
					(size 1.27 1.27)
					(thickness 0.15)
				)
				(justify left bottom)
				(hide yes)
			)
		)
		(property "Description" ""
			(at 182.88 93.98 0)
			(effects
				(font
					(size 1.27 1.27)
				)
			)
		)
		(property "Author" "Antmicro"
			(at 191.77 101.6 0)
			(effects
				(font
					(size 1.27 1.27)
					(thickness 0.15)
				)
				(justify left bottom)
				(hide yes)
			)
		)
		(property "License" "Apache-2.0"
			(at 191.77 104.14 0)
			(effects
				(font
					(size 1.27 1.27)
					(thickness 0.15)
				)
				(justify left bottom)
				(hide yes)
			)
		)
		(pin "1"
		)
		(instances
			(project "k410t-devboard"
				(path ""
					(reference "#PWR0106")
					(unit 1)
				)
			)
		)
	)
	(symbol
		(lib_id "antmicropower:GNDD")
		(at 158.75 208.28 0)
		(unit 1)
		(exclude_from_sim no)
		(in_bom yes)
		(on_board yes)
		(dnp no)
		(property "Reference" "#PWR098"
			(at 158.75 214.63 0)
			(effects
				(font
					(size 1.27 1.27)
				)
				(hide yes)
			)
		)
		(property "Value" "GNDD"
			(at 158.75 212.09 0)
			(effects
				(font
					(size 1.27 1.27)
				)
			)
		)
		(property "Footprint" ""
			(at 158.75 208.28 0)
			(effects
				(font
					(size 1.27 1.27)
				)
				(hide yes)
			)
		)
		(property "Datasheet" ""
			(at 158.75 208.28 0)
			(effects
				(font
					(size 1.27 1.27)
				)
				(hide yes)
			)
		)
		(property "Description" ""
			(at 158.75 208.28 0)
			(effects
				(font
					(size 1.27 1.27)
				)
			)
		)
		(property "Author" "Antmicro"
			(at 173.99 215.9 0)
			(effects
				(font
					(size 1.27 1.27)
					(thickness 0.15)
				)
				(justify left bottom)
				(hide yes)
			)
		)
		(property "License" "Apache-2.0"
			(at 173.99 218.44 0)
			(effects
				(font
					(size 1.27 1.27)
					(thickness 0.15)
				)
				(justify left bottom)
				(hide yes)
			)
		)
		(pin "1"
		)
		(instances
			(project "k410t-devboard"
				(path ""
					(reference "#PWR098")
					(unit 1)
				)
			)
		)
	)
	(symbol
		(lib_id "antmicroFuses:F_10A_1206")
		(at 48.26 34.29 0)
		(unit 1)
		(exclude_from_sim no)
		(in_bom yes)
		(on_board yes)
		(dnp no)
		(fields_autoplaced yes)
		(property "Reference" "F1"
			(at 50.8 29.21 0)
			(effects
				(font
					(size 1.27 1.27)
				)
			)
		)
		(property "Value" "F_10A_1206"
			(at 68.58 41.91 0)
			(effects
				(font
					(size 1.27 1.27)
					(thickness 0.15)
				)
				(justify left bottom)
				(hide yes)
			)
		)
		(property "Footprint" "antmicro-footprints:F_1206_3216Metric"
			(at 68.58 44.45 0)
			(effects
				(font
					(size 1.27 1.27)
					(thickness 0.15)
				)
				(justify left bottom)
				(hide yes)
			)
		)
		(property "Datasheet" "https://us.schurter.com/pdf/english/typ_UST_1206.pdf"
			(at 68.58 46.99 0)
			(effects
				(font
					(size 1.27 1.27)
					(thickness 0.15)
				)
				(justify left bottom)
				(hide yes)
			)
		)
		(property "Description" ""
			(at 48.26 34.29 0)
			(effects
				(font
					(size 1.27 1.27)
				)
			)
		)
		(property "Manufacturer" "Schurter"
			(at 68.58 49.53 0)
			(effects
				(font
					(size 1.27 1.27)
					(thickness 0.15)
				)
				(justify left bottom)
				(hide yes)
			)
		)
		(property "MPN" "3413.0328.22"
			(at 50.8 31.75 0)
			(effects
				(font
					(size 1.27 1.27)
					(thickness 0.15)
				)
			)
		)
		(property "Author" "Antmicro"
			(at 68.58 54.61 0)
			(effects
				(font
					(size 1.27 1.27)
					(thickness 0.15)
				)
				(justify left bottom)
				(hide yes)
			)
		)
		(property "License" "Apache-2.0"
			(at 68.58 57.15 0)
			(effects
				(font
					(size 1.27 1.27)
					(thickness 0.15)
				)
				(justify left bottom)
				(hide yes)
			)
		)
		(pin "1"
		)
		(pin "2"
		)
		(instances
			(project "k410t-devboard"
				(path ""
					(reference "F1")
					(unit 1)
				)
			)
		)
	)
	(symbol
		(lib_id "antmicroTVSDiodes:CD-MMBL110S")
		(at 53.34 205.74 0)
		(unit 1)
		(exclude_from_sim no)
		(in_bom yes)
		(on_board yes)
		(dnp no)
		(fields_autoplaced yes)
		(property "Reference" "D5"
			(at 62.23 199.39 0)
			(effects
				(font
					(size 1.27 1.27)
				)
			)
		)
		(property "Value" "CD-MMBL110S"
			(at 62.23 201.93 0)
			(effects
				(font
					(size 1.27 1.27)
					(thickness 0.15)
				)
				(hide yes)
			)
		)
		(property "Footprint" "antmicro-footprints:DFN3538"
			(at 85.09 215.9 0)
			(effects
				(font
					(size 1.27 1.27)
					(thickness 0.15)
				)
				(justify left bottom)
				(hide yes)
			)
		)
		(property "Datasheet" "https://www.bourns.com/docs/product-datasheets/CD-MMBL110S.pdf"
			(at 85.09 218.44 0)
			(effects
				(font
					(size 1.27 1.27)
					(thickness 0.15)
				)
				(justify left bottom)
				(hide yes)
			)
		)
		(property "Description" ""
			(at 53.34 205.74 0)
			(effects
				(font
					(size 1.27 1.27)
				)
			)
		)
		(property "MPN" "CD-MMBL110S"
			(at 62.23 201.93 0)
			(effects
				(font
					(size 1.27 1.27)
					(thickness 0.15)
				)
			)
		)
		(property "Manufacturer" "Bourns"
			(at 85.09 223.52 0)
			(effects
				(font
					(size 1.27 1.27)
					(thickness 0.15)
				)
				(justify left bottom)
				(hide yes)
			)
		)
		(property "Author" "Antmicro"
			(at 85.09 226.06 0)
			(effects
				(font
					(size 1.27 1.27)
					(thickness 0.15)
				)
				(justify left bottom)
				(hide yes)
			)
		)
		(property "License" "Apache-2.0"
			(at 85.09 228.6 0)
			(effects
				(font
					(size 1.27 1.27)
					(thickness 0.15)
				)
				(justify left bottom)
				(hide yes)
			)
		)
		(pin "1"
		)
		(pin "2"
		)
		(pin "3"
		)
		(pin "4"
		)
		(instances
			(project "k410t-devboard"
				(path ""
					(reference "D5")
					(unit 1)
				)
			)
		)
	)
	(symbol
		(lib_id "antmicroCapacitorsmisc:C_22u_100V_2220")
		(at 158.75 198.12 90)
		(unit 1)
		(exclude_from_sim no)
		(in_bom yes)
		(on_board yes)
		(dnp no)
		(property "Reference" "C199"
			(at 158.75 193.04 90)
			(effects
				(font
					(size 1.27 1.27)
				)
				(justify right)
			)
		)
		(property "Value" "C_22u_100V_2220"
			(at 168.91 177.8 0)
			(effects
				(font
					(size 1.27 1.27)
					(thickness 0.15)
				)
				(justify left bottom)
				(hide yes)
			)
		)
		(property "Footprint" "antmicro-footprints:C_2220_5650Metric"
			(at 171.45 177.8 0)
			(effects
				(font
					(size 1.27 1.27)
					(thickness 0.15)
				)
				(justify left bottom)
				(hide yes)
			)
		)
		(property "Datasheet" "https://product.tdk.com/en/search/capacitor/ceramic/mlcc/info?part_no=C5750X7S2A226M280KB"
			(at 173.99 177.8 0)
			(effects
				(font
					(size 1.27 1.27)
					(thickness 0.15)
				)
				(justify left bottom)
				(hide yes)
			)
		)
		(property "Description" ""
			(at 158.75 198.12 0)
			(effects
				(font
					(size 1.27 1.27)
				)
			)
		)
		(property "Manufacturer" "TDK"
			(at 179.07 177.8 0)
			(effects
				(font
					(size 1.27 1.27)
					(thickness 0.15)
				)
				(justify left bottom)
				(hide yes)
			)
		)
		(property "MPN" "C5750X7S2A226M280KB"
			(at 176.53 177.8 0)
			(effects
				(font
					(size 1.27 1.27)
					(thickness 0.15)
				)
				(justify left bottom)
				(hide yes)
			)
		)
		(property "Val" "22u"
			(at 158.75 198.12 90)
			(effects
				(font
					(size 1.27 1.27)
					(thickness 0.15)
				)
				(justify right)
			)
		)
		(property "License" "Apache-2.0"
			(at 181.61 177.8 0)
			(effects
				(font
					(size 1.27 1.27)
					(thickness 0.15)
				)
				(justify left bottom)
				(hide yes)
			)
		)
		(property "Author" "Antmicro"
			(at 184.15 177.8 0)
			(effects
				(font
					(size 1.27 1.27)
					(thickness 0.15)
				)
				(justify left bottom)
				(hide yes)
			)
		)
		(property "Voltage" "100V"
			(at 158.75 200.66 90)
			(effects
				(font
					(size 1.27 1.27)
				)
				(justify right)
			)
		)
		(property "Dielectric" "X7S"
			(at 189.23 177.8 0)
			(effects
				(font
					(size 1.27 1.27)
				)
				(justify left bottom)
				(hide yes)
			)
		)
		(pin "1"
		)
		(pin "2"
		)
		(instances
			(project "k410t-devboard"
				(path ""
					(reference "C199")
					(unit 1)
				)
			)
		)
	)
	(symbol
		(lib_id "antmicropower:+3.3V")
		(at 179.07 116.84 0)
		(unit 1)
		(exclude_from_sim no)
		(in_bom yes)
		(on_board yes)
		(dnp no)
		(property "Reference" "#PWR0107"
			(at 179.07 120.65 0)
			(effects
				(font
					(size 1.27 1.27)
				)
				(hide yes)
			)
		)
		(property "Value" "+3V3"
			(at 179.07 113.284 0)
			(effects
				(font
					(size 1.27 1.27)
				)
			)
		)
		(property "Footprint" ""
			(at 179.07 116.84 0)
			(effects
				(font
					(size 1.27 1.27)
				)
				(hide yes)
			)
		)
		(property "Datasheet" ""
			(at 179.07 116.84 0)
			(effects
				(font
					(size 1.27 1.27)
				)
				(hide yes)
			)
		)
		(property "Description" ""
			(at 179.07 116.84 0)
			(effects
				(font
					(size 1.27 1.27)
				)
			)
		)
		(pin "1"
		)
		(instances
			(project "k410t-devboard"
				(path ""
					(reference "#PWR0107")
					(unit 1)
				)
			)
		)
	)
	(symbol
		(lib_id "antmicroResistors0402:R_24k9_0402")
		(at 148.59 236.22 90)
		(unit 1)
		(exclude_from_sim no)
		(in_bom yes)
		(on_board yes)
		(dnp no)
		(fields_autoplaced yes)
		(property "Reference" "R55"
			(at 146.05 232.4099 90)
			(effects
				(font
					(size 1.27 1.27)
				)
				(justify left)
			)
		)
		(property "Value" "R_24k9_0402"
			(at 161.29 215.9 0)
			(effects
				(font
					(size 1.27 1.27)
					(thickness 0.15)
				)
				(justify left bottom)
				(hide yes)
			)
		)
		(property "Footprint" "antmicro-footprints:R_0402_1005Metric"
			(at 163.83 215.9 0)
			(effects
				(font
					(size 1.27 1.27)
					(thickness 0.15)
				)
				(justify left bottom)
				(hide yes)
			)
		)
		(property "Datasheet" "https://www.bourns.com/docs/product-datasheets/cr.pdf"
			(at 166.37 215.9 0)
			(effects
				(font
					(size 1.27 1.27)
					(thickness 0.15)
				)
				(justify left bottom)
				(hide yes)
			)
		)
		(property "Description" ""
			(at 148.59 236.22 0)
			(effects
				(font
					(size 1.27 1.27)
				)
			)
		)
		(property "Manufacturer" "Bourns"
			(at 171.45 215.9 0)
			(effects
				(font
					(size 1.27 1.27)
					(thickness 0.15)
				)
				(justify left bottom)
				(hide yes)
			)
		)
		(property "MPN" "CR0402-FX-2492GLF"
			(at 168.91 215.9 0)
			(effects
				(font
					(size 1.27 1.27)
					(thickness 0.15)
				)
				(justify left bottom)
				(hide yes)
			)
		)
		(property "Val" "24k9"
			(at 146.05 234.9499 90)
			(effects
				(font
					(size 1.27 1.27)
					(thickness 0.15)
				)
				(justify left)
			)
		)
		(property "License" "Apache-2.0"
			(at 173.99 215.9 0)
			(effects
				(font
					(size 1.27 1.27)
					(thickness 0.15)
				)
				(justify left bottom)
				(hide yes)
			)
		)
		(property "Author" "Antmicro"
			(at 176.53 215.9 0)
			(effects
				(font
					(size 1.27 1.27)
					(thickness 0.15)
				)
				(justify left bottom)
				(hide yes)
			)
		)
		(property "Tolerance" "1%"
			(at 158.75 215.9 0)
			(effects
				(font
					(size 1.27 1.27)
				)
				(justify left bottom)
				(hide yes)
			)
		)
		(pin "1"
		)
		(pin "2"
		)
		(instances
			(project "k410t-devboard"
				(path ""
					(reference "R55")
					(unit 1)
				)
			)
		)
	)
	(symbol
		(lib_id "antmicroCapacitorsmisc:C_22u_100V_2220")
		(at 137.16 198.12 270)
		(mirror x)
		(unit 1)
		(exclude_from_sim no)
		(in_bom yes)
		(on_board yes)
		(dnp no)
		(property "Reference" "C195"
			(at 137.16 193.04 90)
			(effects
				(font
					(size 1.27 1.27)
				)
				(justify left)
			)
		)
		(property "Value" "C_22u_100V_2220"
			(at 127 177.8 0)
			(effects
				(font
					(size 1.27 1.27)
					(thickness 0.15)
				)
				(justify left bottom)
				(hide yes)
			)
		)
		(property "Footprint" "antmicro-footprints:C_2220_5650Metric"
			(at 124.46 177.8 0)
			(effects
				(font
					(size 1.27 1.27)
					(thickness 0.15)
				)
				(justify left bottom)
				(hide yes)
			)
		)
		(property "Datasheet" "https://product.tdk.com/en/search/capacitor/ceramic/mlcc/info?part_no=C5750X7S2A226M280KB"
			(at 121.92 177.8 0)
			(effects
				(font
					(size 1.27 1.27)
					(thickness 0.15)
				)
				(justify left bottom)
				(hide yes)
			)
		)
		(property "Description" ""
			(at 137.16 198.12 0)
			(effects
				(font
					(size 1.27 1.27)
				)
			)
		)
		(property "Manufacturer" "TDK"
			(at 116.84 177.8 0)
			(effects
				(font
					(size 1.27 1.27)
					(thickness 0.15)
				)
				(justify left bottom)
				(hide yes)
			)
		)
		(property "MPN" "C5750X7S2A226M280KB"
			(at 119.38 177.8 0)
			(effects
				(font
					(size 1.27 1.27)
					(thickness 0.15)
				)
				(justify left bottom)
				(hide yes)
			)
		)
		(property "Val" "22u"
			(at 137.16 198.12 90)
			(effects
				(font
					(size 1.27 1.27)
					(thickness 0.15)
				)
				(justify left)
			)
		)
		(property "License" "Apache-2.0"
			(at 114.3 177.8 0)
			(effects
				(font
					(size 1.27 1.27)
					(thickness 0.15)
				)
				(justify left bottom)
				(hide yes)
			)
		)
		(property "Author" "Antmicro"
			(at 111.76 177.8 0)
			(effects
				(font
					(size 1.27 1.27)
					(thickness 0.15)
				)
				(justify left bottom)
				(hide yes)
			)
		)
		(property "Voltage" "100V"
			(at 137.16 200.66 90)
			(effects
				(font
					(size 1.27 1.27)
				)
				(justify left)
			)
		)
		(property "Dielectric" "X7S"
			(at 106.68 177.8 0)
			(effects
				(font
					(size 1.27 1.27)
				)
				(justify left bottom)
				(hide yes)
			)
		)
		(pin "1"
		)
		(pin "2"
		)
		(instances
			(project "k410t-devboard"
				(path ""
					(reference "C195")
					(unit 1)
				)
			)
		)
	)
	(symbol
		(lib_id "antmicroCapacitors0402:C_1u_0402")
		(at 170.18 147.32 90)
		(mirror x)
		(unit 1)
		(exclude_from_sim no)
		(in_bom yes)
		(on_board yes)
		(dnp no)
		(property "Reference" "C192"
			(at 170.815 147.955 90)
			(effects
				(font
					(size 1.27 1.27)
				)
				(justify right)
			)
		)
		(property "Value" "C_1u_0402"
			(at 180.34 167.64 0)
			(effects
				(font
					(size 1.27 1.27)
					(thickness 0.15)
				)
				(justify left bottom)
				(hide yes)
			)
		)
		(property "Footprint" "antmicro-footprints:C_0402_1005Metric"
			(at 182.88 167.64 0)
			(effects
				(font
					(size 1.27 1.27)
					(thickness 0.15)
				)
				(justify left bottom)
				(hide yes)
			)
		)
		(property "Datasheet" "https://product.tdk.com/en/search/capacitor/ceramic/mlcc/info?part_no=C1005X6S1A105K050BC"
			(at 185.42 167.64 0)
			(effects
				(font
					(size 1.27 1.27)
					(thickness 0.15)
				)
				(justify left bottom)
				(hide yes)
			)
		)
		(property "Description" ""
			(at 170.18 147.32 0)
			(effects
				(font
					(size 1.27 1.27)
				)
			)
		)
		(property "Manufacturer" "TDK"
			(at 190.5 167.64 0)
			(effects
				(font
					(size 1.27 1.27)
					(thickness 0.15)
				)
				(justify left bottom)
				(hide yes)
			)
		)
		(property "MPN" "C1005X6S1A105K050BC"
			(at 187.96 167.64 0)
			(effects
				(font
					(size 1.27 1.27)
					(thickness 0.15)
				)
				(justify left bottom)
				(hide yes)
			)
		)
		(property "Val" "1u"
			(at 170.815 151.765 90)
			(effects
				(font
					(size 1.27 1.27)
					(thickness 0.15)
				)
				(justify right)
			)
		)
		(property "License" "Apache-2.0"
			(at 193.04 167.64 0)
			(effects
				(font
					(size 1.27 1.27)
					(thickness 0.15)
				)
				(justify left bottom)
				(hide yes)
			)
		)
		(property "Author" "Antmicro"
			(at 195.58 167.64 0)
			(effects
				(font
					(size 1.27 1.27)
					(thickness 0.15)
				)
				(justify left bottom)
				(hide yes)
			)
		)
		(property "Voltage" ""
			(at 198.12 167.64 0)
			(effects
				(font
					(size 1.27 1.27)
				)
				(justify left bottom)
				(hide yes)
			)
		)
		(property "Dielectric" ""
			(at 200.66 167.64 0)
			(effects
				(font
					(size 1.27 1.27)
				)
				(justify left bottom)
				(hide yes)
			)
		)
		(pin "1"
		)
		(pin "2"
		)
		(instances
			(project "k410t-devboard"
				(path ""
					(reference "C192")
					(unit 1)
				)
			)
		)
	)
	(symbol
		(lib_id "antmicroResistors0402:R_0R_0402")
		(at 204.47 241.3 90)
		(unit 1)
		(exclude_from_sim no)
		(in_bom yes)
		(on_board yes)
		(dnp no)
		(property "Reference" "R60"
			(at 205.74 237.49 90)
			(effects
				(font
					(size 1.27 1.27)
				)
				(justify right)
			)
		)
		(property "Value" "R_0R_0402"
			(at 217.17 220.98 0)
			(effects
				(font
					(size 1.27 1.27)
					(thickness 0.15)
				)
				(justify left bottom)
				(hide yes)
			)
		)
		(property "Footprint" "antmicro-footprints:R_0402_1005Metric"
			(at 219.71 220.98 0)
			(effects
				(font
					(size 1.27 1.27)
					(thickness 0.15)
				)
				(justify left bottom)
				(hide yes)
			)
		)
		(property "Datasheet" "https://industrial.panasonic.com/cdbs/www-data/pdf/RDA0000/AOA0000C301.pdf"
			(at 222.25 220.98 0)
			(effects
				(font
					(size 1.27 1.27)
					(thickness 0.15)
				)
				(justify left bottom)
				(hide yes)
			)
		)
		(property "Description" ""
			(at 204.47 241.3 0)
			(effects
				(font
					(size 1.27 1.27)
				)
			)
		)
		(property "Manufacturer" "Panasonic"
			(at 227.33 220.98 0)
			(effects
				(font
					(size 1.27 1.27)
					(thickness 0.15)
				)
				(justify left bottom)
				(hide yes)
			)
		)
		(property "MPN" "ERJ2GE0R00X"
			(at 224.79 220.98 0)
			(effects
				(font
					(size 1.27 1.27)
					(thickness 0.15)
				)
				(justify left bottom)
				(hide yes)
			)
		)
		(property "Val" "0R"
			(at 205.74 240.03 90)
			(effects
				(font
					(size 1.27 1.27)
					(thickness 0.15)
				)
				(justify right)
			)
		)
		(property "License" "Apache-2.0"
			(at 229.87 220.98 0)
			(effects
				(font
					(size 1.27 1.27)
					(thickness 0.15)
				)
				(justify left bottom)
				(hide yes)
			)
		)
		(property "Author" "Antmicro"
			(at 232.41 220.98 0)
			(effects
				(font
					(size 1.27 1.27)
					(thickness 0.15)
				)
				(justify left bottom)
				(hide yes)
			)
		)
		(property "Tolerance" "~"
			(at 214.63 220.98 0)
			(effects
				(font
					(size 1.27 1.27)
				)
				(justify left bottom)
				(hide yes)
			)
		)
		(property "Current" "1A"
			(at 207.01 241.2999 90)
			(effects
				(font
					(size 1.27 1.27)
					(thickness 0.15)
				)
				(justify right)
				(hide yes)
			)
		)
		(pin "1"
		)
		(pin "2"
		)
		(instances
			(project "k410t-devboard"
				(path ""
					(reference "R60")
					(unit 1)
				)
			)
		)
	)
	(symbol
		(lib_id "antmicroTransistorsFETsMOSFETsSingle:SI7613DN-T1-GE3")
		(at 339.09 41.91 90)
		(unit 1)
		(exclude_from_sim no)
		(in_bom yes)
		(on_board yes)
		(dnp no)
		(fields_autoplaced yes)
		(property "Reference" "Q5"
			(at 336.55 27.94 90)
			(effects
				(font
					(size 1.27 1.27)
				)
			)
		)
		(property "Value" "SI7613DN-T1-GE3"
			(at 336.55 29.21 90)
			(effects
				(font
					(size 1.27 1.27)
					(thickness 0.15)
				)
				(hide yes)
			)
		)
		(property "Footprint" "antmicro-footprints:Vishay_PowerPAK_1212-8_Single"
			(at 337.82 26.67 0)
			(effects
				(font
					(size 1.27 1.27)
					(thickness 0.15)
				)
				(justify left bottom)
				(hide yes)
			)
		)
		(property "Datasheet" "https://www.vishay.com/docs/64809/si7613dn.pdf"
			(at 340.36 26.67 0)
			(effects
				(font
					(size 1.27 1.27)
					(thickness 0.15)
				)
				(justify left bottom)
				(hide yes)
			)
		)
		(property "Description" ""
			(at 339.09 41.91 0)
			(effects
				(font
					(size 1.27 1.27)
				)
			)
		)
		(property "MPN" "SI7613DN-T1-GE3"
			(at 336.55 30.48 90)
			(effects
				(font
					(size 1.27 1.27)
					(thickness 0.15)
				)
			)
		)
		(property "Manufacturer" "Vishay"
			(at 346.71 26.67 0)
			(effects
				(font
					(size 1.27 1.27)
					(thickness 0.15)
				)
				(justify left bottom)
				(hide yes)
			)
		)
		(property "Author" "Antmicro"
			(at 349.25 26.67 0)
			(effects
				(font
					(size 1.27 1.27)
					(thickness 0.15)
				)
				(justify left bottom)
				(hide yes)
			)
		)
		(property "License" "Apache-2.0"
			(at 351.79 26.67 0)
			(effects
				(font
					(size 1.27 1.27)
					(thickness 0.15)
				)
				(justify left bottom)
				(hide yes)
			)
		)
		(pin "1"
		)
		(pin "2"
		)
		(pin "3"
		)
		(pin "4"
		)
		(pin "5"
		)
		(instances
			(project "k410t-devboard"
				(path ""
					(reference "Q5")
					(unit 1)
				)
			)
		)
	)
	(symbol
		(lib_id "antmicroBarrelPowerConnectors:BarrelJack_Pin2mm_MJ-179PH")
		(at 38.1 34.29 0)
		(unit 1)
		(exclude_from_sim no)
		(in_bom yes)
		(on_board yes)
		(dnp no)
		(fields_autoplaced yes)
		(property "Reference" "J2"
			(at 30.48 27.94 0)
			(effects
				(font
					(size 1.27 1.27)
				)
			)
		)
		(property "Value" "BarrelJack_Pin2mm_MJ-179PH"
			(at 33.02 41.91 0)
			(effects
				(font
					(size 1.27 1.27)
					(thickness 0.15)
				)
				(justify right)
				(hide yes)
			)
		)
		(property "Footprint" "antmicro-footprints:BarrelJack_Pin2mm_MJ-179PH"
			(at 55.88 46.99 0)
			(effects
				(font
					(size 1.27 1.27)
					(thickness 0.15)
				)
				(justify left bottom)
				(hide yes)
			)
		)
		(property "Datasheet" "https://www.farnell.com/datasheets/3167288.pdf"
			(at 55.88 49.53 0)
			(effects
				(font
					(size 1.27 1.27)
					(thickness 0.15)
				)
				(justify left bottom)
				(hide yes)
			)
		)
		(property "Description" ""
			(at 38.1 34.29 0)
			(effects
				(font
					(size 1.27 1.27)
				)
			)
		)
		(property "Manufacturer" "Multicomp Pro"
			(at 55.88 52.07 0)
			(effects
				(font
					(size 1.27 1.27)
					(thickness 0.15)
				)
				(justify left bottom)
				(hide yes)
			)
		)
		(property "MPN" "MJ-179PH"
			(at 30.48 30.48 0)
			(effects
				(font
					(size 1.27 1.27)
					(thickness 0.15)
				)
			)
		)
		(property "Author" "Antmicro"
			(at 55.88 54.61 0)
			(effects
				(font
					(size 1.27 1.27)
					(thickness 0.15)
				)
				(justify left bottom)
				(hide yes)
			)
		)
		(property "License" "Apache-2.0"
			(at 55.88 57.15 0)
			(effects
				(font
					(size 1.27 1.27)
					(thickness 0.15)
				)
				(justify left bottom)
				(hide yes)
			)
		)
		(pin "1"
		)
		(pin "2"
		)
		(pin "3"
		)
		(instances
			(project "k410t-devboard"
				(path ""
					(reference "J2")
					(unit 1)
				)
			)
		)
	)
	(symbol
		(lib_id "antmicropower:GND")
		(at 350.52 105.41 0)
		(unit 1)
		(exclude_from_sim no)
		(in_bom yes)
		(on_board yes)
		(dnp no)
		(fields_autoplaced yes)
		(property "Reference" "#PWR0116"
			(at 350.52 111.76 0)
			(effects
				(font
					(size 1.27 1.27)
				)
				(hide yes)
			)
		)
		(property "Value" "GND"
			(at 350.52 109.22 0)
			(effects
				(font
					(size 1.27 1.27)
				)
			)
		)
		(property "Footprint" ""
			(at 359.41 113.03 0)
			(effects
				(font
					(size 1.27 1.27)
					(thickness 0.15)
				)
				(justify left bottom)
				(hide yes)
			)
		)
		(property "Datasheet" ""
			(at 359.41 118.11 0)
			(effects
				(font
					(size 1.27 1.27)
					(thickness 0.15)
				)
				(justify left bottom)
				(hide yes)
			)
		)
		(property "Description" ""
			(at 350.52 105.41 0)
			(effects
				(font
					(size 1.27 1.27)
				)
			)
		)
		(property "Author" "Antmicro"
			(at 359.41 113.03 0)
			(effects
				(font
					(size 1.27 1.27)
					(thickness 0.15)
				)
				(justify left bottom)
				(hide yes)
			)
		)
		(property "License" "Apache-2.0"
			(at 359.41 115.57 0)
			(effects
				(font
					(size 1.27 1.27)
					(thickness 0.15)
				)
				(justify left bottom)
				(hide yes)
			)
		)
		(pin "1"
		)
		(instances
			(project "k410t-devboard"
				(path ""
					(reference "#PWR0116")
					(unit 1)
				)
			)
		)
	)
	(symbol
		(lib_id "antmicroResistors0402:R_0R_0402")
		(at 125.73 264.16 0)
		(unit 1)
		(exclude_from_sim no)
		(in_bom yes)
		(on_board yes)
		(dnp no)
		(property "Reference" "R49"
			(at 133.35 262.89 0)
			(effects
				(font
					(size 1.27 1.27)
				)
			)
		)
		(property "Value" "R_0R_0402"
			(at 146.05 276.86 0)
			(effects
				(font
					(size 1.27 1.27)
					(thickness 0.15)
				)
				(justify left bottom)
				(hide yes)
			)
		)
		(property "Footprint" "antmicro-footprints:R_0402_1005Metric"
			(at 146.05 279.4 0)
			(effects
				(font
					(size 1.27 1.27)
					(thickness 0.15)
				)
				(justify left bottom)
				(hide yes)
			)
		)
		(property "Datasheet" "https://industrial.panasonic.com/cdbs/www-data/pdf/RDA0000/AOA0000C301.pdf"
			(at 146.05 281.94 0)
			(effects
				(font
					(size 1.27 1.27)
					(thickness 0.15)
				)
				(justify left bottom)
				(hide yes)
			)
		)
		(property "Description" ""
			(at 125.73 264.16 0)
			(effects
				(font
					(size 1.27 1.27)
				)
			)
		)
		(property "Manufacturer" "Panasonic"
			(at 146.05 287.02 0)
			(effects
				(font
					(size 1.27 1.27)
					(thickness 0.15)
				)
				(justify left bottom)
				(hide yes)
			)
		)
		(property "MPN" "ERJ2GE0R00X"
			(at 146.05 284.48 0)
			(effects
				(font
					(size 1.27 1.27)
					(thickness 0.15)
				)
				(justify left bottom)
				(hide yes)
			)
		)
		(property "Val" "0R"
			(at 123.825 262.89 0)
			(effects
				(font
					(size 1.27 1.27)
					(thickness 0.15)
				)
			)
		)
		(property "License" "Apache-2.0"
			(at 146.05 289.56 0)
			(effects
				(font
					(size 1.27 1.27)
					(thickness 0.15)
				)
				(justify left bottom)
				(hide yes)
			)
		)
		(property "Author" "Antmicro"
			(at 146.05 292.1 0)
			(effects
				(font
					(size 1.27 1.27)
					(thickness 0.15)
				)
				(justify left bottom)
				(hide yes)
			)
		)
		(property "Tolerance" "~"
			(at 146.05 274.32 0)
			(effects
				(font
					(size 1.27 1.27)
				)
				(justify left bottom)
				(hide yes)
			)
		)
		(property "Current" "1A"
			(at 128.27 273.05 0)
			(effects
				(font
					(size 1.27 1.27)
					(thickness 0.15)
				)
				(hide yes)
			)
		)
		(pin "1"
		)
		(pin "2"
		)
		(instances
			(project "k410t-devboard"
				(path ""
					(reference "R49")
					(unit 1)
				)
			)
		)
	)
	(symbol
		(lib_id "antmicropower:+3.3V")
		(at 172.72 116.84 0)
		(unit 1)
		(exclude_from_sim no)
		(in_bom yes)
		(on_board yes)
		(dnp no)
		(property "Reference" "#PWR0103"
			(at 172.72 120.65 0)
			(effects
				(font
					(size 1.27 1.27)
				)
				(hide yes)
			)
		)
		(property "Value" "+3V3"
			(at 172.72 113.284 0)
			(effects
				(font
					(size 1.27 1.27)
				)
			)
		)
		(property "Footprint" ""
			(at 172.72 116.84 0)
			(effects
				(font
					(size 1.27 1.27)
				)
				(hide yes)
			)
		)
		(property "Datasheet" ""
			(at 172.72 116.84 0)
			(effects
				(font
					(size 1.27 1.27)
				)
				(hide yes)
			)
		)
		(property "Description" ""
			(at 172.72 116.84 0)
			(effects
				(font
					(size 1.27 1.27)
				)
			)
		)
		(pin "1"
		)
		(instances
			(project "k410t-devboard"
				(path ""
					(reference "#PWR0103")
					(unit 1)
				)
			)
		)
	)
	(symbol
		(lib_id "antmicroResistors0402:R_1k_0402")
		(at 172.72 87.63 270)
		(unit 1)
		(exclude_from_sim no)
		(in_bom yes)
		(on_board yes)
		(dnp no)
		(fields_autoplaced yes)
		(property "Reference" "R57"
			(at 175.26 88.8999 90)
			(effects
				(font
					(size 1.27 1.27)
				)
				(justify left)
			)
		)
		(property "Value" "R_1k_0402"
			(at 160.02 107.95 0)
			(effects
				(font
					(size 1.27 1.27)
					(thickness 0.15)
				)
				(justify left bottom)
				(hide yes)
			)
		)
		(property "Footprint" "antmicro-footprints:R_0402_1005Metric"
			(at 157.48 107.95 0)
			(effects
				(font
					(size 1.27 1.27)
					(thickness 0.15)
				)
				(justify left bottom)
				(hide yes)
			)
		)
		(property "Datasheet" "https://www.bourns.com/docs/product-datasheets/cr.pdf"
			(at 154.94 107.95 0)
			(effects
				(font
					(size 1.27 1.27)
					(thickness 0.15)
				)
				(justify left bottom)
				(hide yes)
			)
		)
		(property "Description" ""
			(at 172.72 87.63 0)
			(effects
				(font
					(size 1.27 1.27)
				)
			)
		)
		(property "Manufacturer" "Bourns"
			(at 149.86 107.95 0)
			(effects
				(font
					(size 1.27 1.27)
					(thickness 0.15)
				)
				(justify left bottom)
				(hide yes)
			)
		)
		(property "MPN" "CR0402-FX-1001GLF"
			(at 152.4 107.95 0)
			(effects
				(font
					(size 1.27 1.27)
					(thickness 0.15)
				)
				(justify left bottom)
				(hide yes)
			)
		)
		(property "Val" "1k"
			(at 175.26 91.4399 90)
			(effects
				(font
					(size 1.27 1.27)
					(thickness 0.15)
				)
				(justify left)
			)
		)
		(property "License" "Apache-2.0"
			(at 147.32 107.95 0)
			(effects
				(font
					(size 1.27 1.27)
					(thickness 0.15)
				)
				(justify left bottom)
				(hide yes)
			)
		)
		(property "Author" "Antmicro"
			(at 144.78 107.95 0)
			(effects
				(font
					(size 1.27 1.27)
					(thickness 0.15)
				)
				(justify left bottom)
				(hide yes)
			)
		)
		(property "Tolerance" "1%"
			(at 162.56 107.95 0)
			(effects
				(font
					(size 1.27 1.27)
				)
				(justify left bottom)
				(hide yes)
			)
		)
		(pin "1"
		)
		(pin "2"
		)
		(instances
			(project "k410t-devboard"
				(path ""
					(reference "R57")
					(unit 1)
				)
			)
		)
	)
	(symbol
		(lib_id "antmicropower:GND")
		(at 111.76 158.75 0)
		(unit 1)
		(exclude_from_sim no)
		(in_bom yes)
		(on_board yes)
		(dnp no)
		(property "Reference" "#PWR090"
			(at 111.76 165.1 0)
			(effects
				(font
					(size 1.27 1.27)
				)
				(hide yes)
			)
		)
		(property "Value" "GND"
			(at 111.76 162.56 0)
			(effects
				(font
					(size 1.27 1.27)
				)
			)
		)
		(property "Footprint" ""
			(at 120.65 166.37 0)
			(effects
				(font
					(size 1.27 1.27)
					(thickness 0.15)
				)
				(justify left bottom)
				(hide yes)
			)
		)
		(property "Datasheet" ""
			(at 120.65 171.45 0)
			(effects
				(font
					(size 1.27 1.27)
					(thickness 0.15)
				)
				(justify left bottom)
				(hide yes)
			)
		)
		(property "Description" ""
			(at 111.76 158.75 0)
			(effects
				(font
					(size 1.27 1.27)
				)
			)
		)
		(property "Author" "Antmicro"
			(at 120.65 166.37 0)
			(effects
				(font
					(size 1.27 1.27)
					(thickness 0.15)
				)
				(justify left bottom)
				(hide yes)
			)
		)
		(property "License" "Apache-2.0"
			(at 120.65 168.91 0)
			(effects
				(font
					(size 1.27 1.27)
					(thickness 0.15)
				)
				(justify left bottom)
				(hide yes)
			)
		)
		(pin "1"
		)
		(instances
			(project "k410t-devboard"
				(path ""
					(reference "#PWR090")
					(unit 1)
				)
			)
		)
	)
	(symbol
		(lib_id "antmicroPMICPowerDistributionSwitchesLoadDrivers:STUSB4500_QFN")
		(at 114.3 120.65 0)
		(unit 1)
		(exclude_from_sim no)
		(in_bom yes)
		(on_board yes)
		(dnp no)
		(fields_autoplaced yes)
		(property "Reference" "U6"
			(at 129.54 113.03 0)
			(effects
				(font
					(size 1.27 1.27)
				)
			)
		)
		(property "Value" "STUSB4500_QFN"
			(at 132.8294 144.78 0)
			(effects
				(font
					(size 1.27 1.27)
				)
				(justify left)
				(hide yes)
			)
		)
		(property "Footprint" "antmicro-footprints:QFN-24-1EP_4x4mm_P0.5_EP2.1x2.1mm"
			(at 114.3 161.29 0)
			(effects
				(font
					(size 1.27 1.27)
				)
				(hide yes)
			)
		)
		(property "Datasheet" "https://www.mouser.com/datasheet/2/389/dm00489312-1799262.pdf"
			(at 114.3 151.13 0)
			(effects
				(font
					(size 1.27 1.27)
				)
				(hide yes)
			)
		)
		(property "Description" ""
			(at 114.3 120.65 0)
			(effects
				(font
					(size 1.27 1.27)
				)
			)
		)
		(property "MPN" "STUSB4500QTR"
			(at 129.54 115.57 0)
			(effects
				(font
					(size 1.27 1.27)
				)
			)
		)
		(property "Manufacturer" "STMicroelectronics"
			(at 114.3 158.75 0)
			(effects
				(font
					(size 1.27 1.27)
				)
				(hide yes)
			)
		)
		(property "Author" "Antmicro"
			(at 160.02 123.19 0)
			(effects
				(font
					(size 1.27 1.27)
					(thickness 0.15)
				)
				(justify left bottom)
				(hide yes)
			)
		)
		(property "License" "Apache-2.0"
			(at 160.02 125.73 0)
			(effects
				(font
					(size 1.27 1.27)
					(thickness 0.15)
				)
				(justify left bottom)
				(hide yes)
			)
		)
		(pin "1"
		)
		(pin "10"
		)
		(pin "11"
		)
		(pin "12"
		)
		(pin "13"
		)
		(pin "14"
		)
		(pin "15"
		)
		(pin "16"
		)
		(pin "17"
		)
		(pin "18"
		)
		(pin "19"
		)
		(pin "2"
		)
		(pin "20"
		)
		(pin "21"
		)
		(pin "22"
		)
		(pin "23"
		)
		(pin "24"
		)
		(pin "25"
		)
		(pin "3"
		)
		(pin "4"
		)
		(pin "5"
		)
		(pin "6"
		)
		(pin "7"
		)
		(pin "8"
		)
		(pin "9"
		)
		(instances
			(project "k410t-devboard"
				(path ""
					(reference "U6")
					(unit 1)
				)
			)
		)
	)
	(symbol
		(lib_id "antmicroResistors0402:R_0R_0402")
		(at 106.68 121.92 270)
		(unit 1)
		(exclude_from_sim no)
		(in_bom yes)
		(on_board yes)
		(dnp no)
		(property "Reference" "R18"
			(at 107.95 123.19 90)
			(effects
				(font
					(size 1.27 1.27)
				)
				(justify left)
			)
		)
		(property "Value" "R_0R_0402"
			(at 93.98 142.24 0)
			(effects
				(font
					(size 1.27 1.27)
					(thickness 0.15)
				)
				(justify left bottom)
				(hide yes)
			)
		)
		(property "Footprint" "antmicro-footprints:R_0402_1005Metric"
			(at 91.44 142.24 0)
			(effects
				(font
					(size 1.27 1.27)
					(thickness 0.15)
				)
				(justify left bottom)
				(hide yes)
			)
		)
		(property "Datasheet" "https://industrial.panasonic.com/cdbs/www-data/pdf/RDA0000/AOA0000C301.pdf"
			(at 88.9 142.24 0)
			(effects
				(font
					(size 1.27 1.27)
					(thickness 0.15)
				)
				(justify left bottom)
				(hide yes)
			)
		)
		(property "Description" ""
			(at 106.68 121.92 0)
			(effects
				(font
					(size 1.27 1.27)
				)
			)
		)
		(property "Manufacturer" "Panasonic"
			(at 83.82 142.24 0)
			(effects
				(font
					(size 1.27 1.27)
					(thickness 0.15)
				)
				(justify left bottom)
				(hide yes)
			)
		)
		(property "MPN" "ERJ2GE0R00X"
			(at 86.36 142.24 0)
			(effects
				(font
					(size 1.27 1.27)
					(thickness 0.15)
				)
				(justify left bottom)
				(hide yes)
			)
		)
		(property "Val" "0R"
			(at 107.95 125.73 90)
			(effects
				(font
					(size 1.27 1.27)
					(thickness 0.15)
				)
				(justify left)
			)
		)
		(property "License" "Apache-2.0"
			(at 81.28 142.24 0)
			(effects
				(font
					(size 1.27 1.27)
					(thickness 0.15)
				)
				(justify left bottom)
				(hide yes)
			)
		)
		(property "Author" "Antmicro"
			(at 78.74 142.24 0)
			(effects
				(font
					(size 1.27 1.27)
					(thickness 0.15)
				)
				(justify left bottom)
				(hide yes)
			)
		)
		(property "Tolerance" "~"
			(at 96.52 142.24 0)
			(effects
				(font
					(size 1.27 1.27)
				)
				(justify left bottom)
				(hide yes)
			)
		)
		(property "Current" "1A"
			(at 106.68 124.46 0)
			(effects
				(font
					(size 1.27 1.27)
					(thickness 0.15)
				)
				(hide yes)
			)
		)
		(pin "1"
		)
		(pin "2"
		)
		(instances
			(project "k410t-devboard"
				(path ""
					(reference "R18")
					(unit 1)
				)
			)
		)
	)
	(symbol
		(lib_id "antmicropower:GND")
		(at 313.69 55.88 0)
		(unit 1)
		(exclude_from_sim no)
		(in_bom yes)
		(on_board yes)
		(dnp no)
		(fields_autoplaced yes)
		(property "Reference" "#PWR0109"
			(at 313.69 62.23 0)
			(effects
				(font
					(size 1.27 1.27)
				)
				(hide yes)
			)
		)
		(property "Value" "GND"
			(at 313.69 59.69 0)
			(effects
				(font
					(size 1.27 1.27)
				)
			)
		)
		(property "Footprint" ""
			(at 322.58 63.5 0)
			(effects
				(font
					(size 1.27 1.27)
					(thickness 0.15)
				)
				(justify left bottom)
				(hide yes)
			)
		)
		(property "Datasheet" ""
			(at 322.58 68.58 0)
			(effects
				(font
					(size 1.27 1.27)
					(thickness 0.15)
				)
				(justify left bottom)
				(hide yes)
			)
		)
		(property "Description" ""
			(at 313.69 55.88 0)
			(effects
				(font
					(size 1.27 1.27)
				)
			)
		)
		(property "Author" "Antmicro"
			(at 322.58 63.5 0)
			(effects
				(font
					(size 1.27 1.27)
					(thickness 0.15)
				)
				(justify left bottom)
				(hide yes)
			)
		)
		(property "License" "Apache-2.0"
			(at 322.58 66.04 0)
			(effects
				(font
					(size 1.27 1.27)
					(thickness 0.15)
				)
				(justify left bottom)
				(hide yes)
			)
		)
		(pin "1"
		)
		(instances
			(project "k410t-devboard"
				(path ""
					(reference "#PWR0109")
					(unit 1)
				)
			)
		)
	)
	(symbol
		(lib_id "antmicropower:GND")
		(at 350.52 55.88 0)
		(unit 1)
		(exclude_from_sim no)
		(in_bom yes)
		(on_board yes)
		(dnp no)
		(fields_autoplaced yes)
		(property "Reference" "#PWR0112"
			(at 350.52 62.23 0)
			(effects
				(font
					(size 1.27 1.27)
				)
				(hide yes)
			)
		)
		(property "Value" "GND"
			(at 350.52 59.69 0)
			(effects
				(font
					(size 1.27 1.27)
				)
			)
		)
		(property "Footprint" ""
			(at 359.41 63.5 0)
			(effects
				(font
					(size 1.27 1.27)
					(thickness 0.15)
				)
				(justify left bottom)
				(hide yes)
			)
		)
		(property "Datasheet" ""
			(at 359.41 68.58 0)
			(effects
				(font
					(size 1.27 1.27)
					(thickness 0.15)
				)
				(justify left bottom)
				(hide yes)
			)
		)
		(property "Description" ""
			(at 350.52 55.88 0)
			(effects
				(font
					(size 1.27 1.27)
				)
			)
		)
		(property "Author" "Antmicro"
			(at 359.41 63.5 0)
			(effects
				(font
					(size 1.27 1.27)
					(thickness 0.15)
				)
				(justify left bottom)
				(hide yes)
			)
		)
		(property "License" "Apache-2.0"
			(at 359.41 66.04 0)
			(effects
				(font
					(size 1.27 1.27)
					(thickness 0.15)
				)
				(justify left bottom)
				(hide yes)
			)
		)
		(pin "1"
		)
		(instances
			(project "k410t-devboard"
				(path ""
					(reference "#PWR0112")
					(unit 1)
				)
			)
		)
	)
	(symbol
		(lib_id "antmicroLEDIndicationDiscrete:LED_G_0603_KP-1608CGCK")
		(at 179.07 130.81 270)
		(mirror x)
		(unit 1)
		(exclude_from_sim no)
		(in_bom yes)
		(on_board yes)
		(dnp no)
		(property "Reference" "D12"
			(at 182.88 128.27 90)
			(effects
				(font
					(size 1.27 1.27)
				)
				(justify left)
			)
		)
		(property "Value" "LED_G_0603_KP-1608CGCK"
			(at 182.245 125.73 90)
			(effects
				(font
					(size 1.27 1.27)
					(thickness 0.15)
				)
				(justify left)
				(hide yes)
			)
		)
		(property "Footprint" "antmicro-footprints:LED_0603_1608Metric_G"
			(at 168.91 107.95 0)
			(effects
				(font
					(size 1.27 1.27)
					(thickness 0.15)
				)
				(justify left bottom)
				(hide yes)
			)
		)
		(property "Datasheet" "http://www.kingbright.com/attachments/file/psearch//000/00/00/KP-1608CGCK(Ver.23B).pdf"
			(at 166.37 107.95 0)
			(effects
				(font
					(size 1.27 1.27)
					(thickness 0.15)
				)
				(justify left bottom)
				(hide yes)
			)
		)
		(property "Description" ""
			(at 179.07 130.81 0)
			(effects
				(font
					(size 1.27 1.27)
				)
			)
		)
		(property "MPN" "KP-1608CGCK"
			(at 163.83 107.95 0)
			(effects
				(font
					(size 1.27 1.27)
					(thickness 0.15)
				)
				(justify left bottom)
				(hide yes)
			)
		)
		(property "Manufacturer" "Kingbright"
			(at 161.29 107.95 0)
			(effects
				(font
					(size 1.27 1.27)
					(thickness 0.15)
				)
				(justify left bottom)
				(hide yes)
			)
		)
		(property "Author" "Antmicro"
			(at 158.75 107.95 0)
			(effects
				(font
					(size 1.27 1.27)
					(thickness 0.15)
				)
				(justify left bottom)
				(hide yes)
			)
		)
		(property "License" "Apache-2.0"
			(at 156.21 107.95 0)
			(effects
				(font
					(size 1.27 1.27)
					(thickness 0.15)
				)
				(justify left bottom)
				(hide yes)
			)
		)
		(property "Color" "Green"
			(at 182.88 125.73 90)
			(effects
				(font
					(size 1.27 1.27)
				)
				(justify left)
			)
		)
		(pin "1"
		)
		(pin "2"
		)
		(instances
			(project "k410t-devboard"
				(path ""
					(reference "D12")
					(unit 1)
				)
			)
		)
	)
	(symbol
		(lib_id "antmicroTVSDiodes:CD-MMBL110S")
		(at 53.34 231.14 0)
		(unit 1)
		(exclude_from_sim no)
		(in_bom no)
		(on_board yes)
		(dnp yes)
		(fields_autoplaced yes)
		(property "Reference" "D6"
			(at 62.23 224.79 0)
			(effects
				(font
					(size 1.27 1.27)
				)
			)
		)
		(property "Value" "CD-MMBL110S"
			(at 62.23 226.695 0)
			(effects
				(font
					(size 1.27 1.27)
					(thickness 0.15)
				)
				(hide yes)
			)
		)
		(property "Footprint" "antmicro-footprints:DFN3538"
			(at 85.09 241.3 0)
			(effects
				(font
					(size 1.27 1.27)
					(thickness 0.15)
				)
				(justify left bottom)
				(hide yes)
			)
		)
		(property "Datasheet" "https://www.bourns.com/docs/product-datasheets/CD-MMBL110S.pdf"
			(at 85.09 243.84 0)
			(effects
				(font
					(size 1.27 1.27)
					(thickness 0.15)
				)
				(justify left bottom)
				(hide yes)
			)
		)
		(property "Description" ""
			(at 53.34 231.14 0)
			(effects
				(font
					(size 1.27 1.27)
				)
			)
		)
		(property "MPN" "CD-MMBL110S"
			(at 62.23 227.33 0)
			(effects
				(font
					(size 1.27 1.27)
					(thickness 0.15)
				)
			)
		)
		(property "Manufacturer" "Bourns"
			(at 85.09 248.92 0)
			(effects
				(font
					(size 1.27 1.27)
					(thickness 0.15)
				)
				(justify left bottom)
				(hide yes)
			)
		)
		(property "Author" "Antmicro"
			(at 85.09 251.46 0)
			(effects
				(font
					(size 1.27 1.27)
					(thickness 0.15)
				)
				(justify left bottom)
				(hide yes)
			)
		)
		(property "License" "Apache-2.0"
			(at 85.09 254 0)
			(effects
				(font
					(size 1.27 1.27)
					(thickness 0.15)
				)
				(justify left bottom)
				(hide yes)
			)
		)
		(property "DNP" "DNP"
			(at 53.34 231.14 0)
			(effects
				(font
					(size 1.27 1.27)
				)
				(hide yes)
			)
		)
		(pin "1"
		)
		(pin "2"
		)
		(pin "3"
		)
		(pin "4"
		)
		(instances
			(project "k410t-devboard"
				(path ""
					(reference "D6")
					(unit 1)
				)
			)
		)
	)
	(symbol
		(lib_id "antmicroResistors0402:R_100k_0402")
		(at 184.15 251.46 90)
		(unit 1)
		(exclude_from_sim no)
		(in_bom yes)
		(on_board yes)
		(dnp no)
		(fields_autoplaced yes)
		(property "Reference" "R38"
			(at 186.69 247.6499 90)
			(effects
				(font
					(size 1.27 1.27)
				)
				(justify right)
			)
		)
		(property "Value" "R_100k_0402"
			(at 196.85 231.14 0)
			(effects
				(font
					(size 1.27 1.27)
					(thickness 0.15)
				)
				(justify left bottom)
				(hide yes)
			)
		)
		(property "Footprint" "antmicro-footprints:R_0402_1005Metric"
			(at 199.39 231.14 0)
			(effects
				(font
					(size 1.27 1.27)
					(thickness 0.15)
				)
				(justify left bottom)
				(hide yes)
			)
		)
		(property "Datasheet" "https://www.bourns.com/docs/product-datasheets/cr.pdf"
			(at 201.93 231.14 0)
			(effects
				(font
					(size 1.27 1.27)
					(thickness 0.15)
				)
				(justify left bottom)
				(hide yes)
			)
		)
		(property "Description" ""
			(at 184.15 251.46 0)
			(effects
				(font
					(size 1.27 1.27)
				)
			)
		)
		(property "Manufacturer" "Bourns"
			(at 207.01 231.14 0)
			(effects
				(font
					(size 1.27 1.27)
					(thickness 0.15)
				)
				(justify left bottom)
				(hide yes)
			)
		)
		(property "MPN" "CR0402-FX-1003GLF"
			(at 204.47 231.14 0)
			(effects
				(font
					(size 1.27 1.27)
					(thickness 0.15)
				)
				(justify left bottom)
				(hide yes)
			)
		)
		(property "Val" "100k"
			(at 186.69 250.1899 90)
			(effects
				(font
					(size 1.27 1.27)
					(thickness 0.15)
				)
				(justify right)
			)
		)
		(property "License" "Apache-2.0"
			(at 209.55 231.14 0)
			(effects
				(font
					(size 1.27 1.27)
					(thickness 0.15)
				)
				(justify left bottom)
				(hide yes)
			)
		)
		(property "Author" "Antmicro"
			(at 212.09 231.14 0)
			(effects
				(font
					(size 1.27 1.27)
					(thickness 0.15)
				)
				(justify left bottom)
				(hide yes)
			)
		)
		(property "Tolerance" "1%"
			(at 194.31 231.14 0)
			(effects
				(font
					(size 1.27 1.27)
				)
				(justify left bottom)
				(hide yes)
			)
		)
		(pin "1"
		)
		(pin "2"
		)
		(instances
			(project "k410t-devboard"
				(path ""
					(reference "R38")
					(unit 1)
				)
			)
		)
	)
	(symbol
		(lib_id "antmicropower:GND")
		(at 160.02 153.67 0)
		(mirror y)
		(unit 1)
		(exclude_from_sim no)
		(in_bom yes)
		(on_board yes)
		(dnp no)
		(property "Reference" "#PWR094"
			(at 160.02 160.02 0)
			(effects
				(font
					(size 1.27 1.27)
				)
				(hide yes)
			)
		)
		(property "Value" "GND"
			(at 160.02 157.48 0)
			(effects
				(font
					(size 1.27 1.27)
				)
			)
		)
		(property "Footprint" ""
			(at 151.13 161.29 0)
			(effects
				(font
					(size 1.27 1.27)
					(thickness 0.15)
				)
				(justify left bottom)
				(hide yes)
			)
		)
		(property "Datasheet" ""
			(at 151.13 166.37 0)
			(effects
				(font
					(size 1.27 1.27)
					(thickness 0.15)
				)
				(justify left bottom)
				(hide yes)
			)
		)
		(property "Description" ""
			(at 160.02 153.67 0)
			(effects
				(font
					(size 1.27 1.27)
				)
			)
		)
		(property "Author" "Antmicro"
			(at 151.13 161.29 0)
			(effects
				(font
					(size 1.27 1.27)
					(thickness 0.15)
				)
				(justify left bottom)
				(hide yes)
			)
		)
		(property "License" "Apache-2.0"
			(at 151.13 163.83 0)
			(effects
				(font
					(size 1.27 1.27)
					(thickness 0.15)
				)
				(justify left bottom)
				(hide yes)
			)
		)
		(pin "1"
		)
		(instances
			(project "k410t-devboard"
				(path ""
					(reference "#PWR094")
					(unit 1)
				)
			)
		)
	)
	(symbol
		(lib_id "antmicroCapacitorsmisc:C_47u_16V_1206")
		(at 224.79 198.12 90)
		(unit 1)
		(exclude_from_sim no)
		(in_bom yes)
		(on_board yes)
		(dnp no)
		(property "Reference" "C202"
			(at 224.79 193.04 90)
			(effects
				(font
					(size 1.27 1.27)
				)
				(justify right)
			)
		)
		(property "Value" "C_47u_16V_1206"
			(at 234.95 177.8 0)
			(effects
				(font
					(size 1.27 1.27)
					(thickness 0.15)
				)
				(justify left bottom)
				(hide yes)
			)
		)
		(property "Footprint" "antmicro-footprints:C_1206_3216Metric"
			(at 237.49 177.8 0)
			(effects
				(font
					(size 1.27 1.27)
					(thickness 0.15)
				)
				(justify left bottom)
				(hide yes)
			)
		)
		(property "Datasheet" "https://product.tdk.com/en/search/capacitor/ceramic/mlcc/info?part_no=C3216X5R1C476M160AB"
			(at 240.03 177.8 0)
			(effects
				(font
					(size 1.27 1.27)
					(thickness 0.15)
				)
				(justify left bottom)
				(hide yes)
			)
		)
		(property "Description" ""
			(at 224.79 198.12 0)
			(effects
				(font
					(size 1.27 1.27)
				)
			)
		)
		(property "Manufacturer" "TDK"
			(at 245.11 177.8 0)
			(effects
				(font
					(size 1.27 1.27)
					(thickness 0.15)
				)
				(justify left bottom)
				(hide yes)
			)
		)
		(property "MPN" "C3216X5R1C476M160AB"
			(at 242.57 177.8 0)
			(effects
				(font
					(size 1.27 1.27)
					(thickness 0.15)
				)
				(justify left bottom)
				(hide yes)
			)
		)
		(property "Val" "47u"
			(at 224.79 198.12 90)
			(effects
				(font
					(size 1.27 1.27)
					(thickness 0.15)
				)
				(justify right)
			)
		)
		(property "License" "Apache-2.0"
			(at 247.65 177.8 0)
			(effects
				(font
					(size 1.27 1.27)
					(thickness 0.15)
				)
				(justify left bottom)
				(hide yes)
			)
		)
		(property "Author" "Antmicro"
			(at 250.19 177.8 0)
			(effects
				(font
					(size 1.27 1.27)
					(thickness 0.15)
				)
				(justify left bottom)
				(hide yes)
			)
		)
		(property "Voltage" "16V"
			(at 224.79 200.66 90)
			(effects
				(font
					(size 1.27 1.27)
				)
				(justify right)
			)
		)
		(property "Dielectric" "X5R"
			(at 255.27 177.8 0)
			(effects
				(font
					(size 1.27 1.27)
				)
				(justify left bottom)
				(hide yes)
			)
		)
		(pin "1"
		)
		(pin "2"
		)
		(instances
			(project "k410t-devboard"
				(path ""
					(reference "C202")
					(unit 1)
				)
			)
		)
	)
	(symbol
		(lib_id "antmicroFerriteBeadsandChips:FB_220Z_2A_Murata-BLM21PG_0805")
		(at 78.74 264.16 0)
		(unit 1)
		(exclude_from_sim no)
		(in_bom no)
		(on_board yes)
		(dnp yes)
		(fields_autoplaced yes)
		(property "Reference" "FB4"
			(at 81.2419 255.27 0)
			(effects
				(font
					(size 1.27 1.27)
				)
			)
		)
		(property "Value" "FB_220Z_2A_Murata-BLM21PG_0805"
			(at 81.28 257.81 0)
			(effects
				(font
					(size 1.27 1.27)
					(thickness 0.15)
				)
				(hide yes)
			)
		)
		(property "Footprint" "antmicro-footprints:FB_0805_2012Metric"
			(at 92.71 269.24 0)
			(effects
				(font
					(size 1.27 1.27)
					(thickness 0.15)
				)
				(justify left bottom)
				(hide yes)
			)
		)
		(property "Datasheet" "https://www.murata.com/products/productdata/8796738977822/ENFA0005.pdf?1653276712000"
			(at 92.71 271.78 0)
			(effects
				(font
					(size 1.27 1.27)
					(thickness 0.15)
				)
				(justify left bottom)
				(hide yes)
			)
		)
		(property "Description" ""
			(at 78.74 264.16 0)
			(effects
				(font
					(size 1.27 1.27)
				)
			)
		)
		(property "MPN" "BLM21PG221SN1D"
			(at 92.71 274.32 0)
			(effects
				(font
					(size 1.27 1.27)
					(thickness 0.15)
				)
				(justify left bottom)
				(hide yes)
			)
		)
		(property "Manufacturer" "Murata"
			(at 92.71 276.86 0)
			(effects
				(font
					(size 1.27 1.27)
					(thickness 0.15)
				)
				(justify left bottom)
				(hide yes)
			)
		)
		(property "Author" "Antmicro"
			(at 92.71 279.4 0)
			(effects
				(font
					(size 1.27 1.27)
					(thickness 0.15)
				)
				(justify left bottom)
				(hide yes)
			)
		)
		(property "License" "Apache-2.0"
			(at 92.71 281.94 0)
			(effects
				(font
					(size 1.27 1.27)
					(thickness 0.15)
				)
				(justify left bottom)
				(hide yes)
			)
		)
		(property "DNP" "DNP"
			(at 81.2419 257.81 0)
			(effects
				(font
					(size 1.27 1.27)
				)
			)
		)
		(property "Val" "220Z/2A"
			(at 81.2419 260.35 0)
			(effects
				(font
					(size 1.27 1.27)
				)
			)
		)
		(property "Current" ""
			(at 99.06 287.02 0)
			(effects
				(font
					(size 1.27 1.27)
					(thickness 0.15)
				)
				(justify left bottom)
				(hide yes)
			)
		)
		(pin "1"
		)
		(pin "2"
		)
		(instances
			(project "k410t-devboard"
				(path ""
					(reference "FB4")
					(unit 1)
				)
			)
		)
	)
	(symbol
		(lib_id "antmicropower:PWR_FLAG")
		(at 128.905 78.74 0)
		(unit 1)
		(exclude_from_sim no)
		(in_bom yes)
		(on_board yes)
		(dnp no)
		(fields_autoplaced yes)
		(property "Reference" "#FLG01"
			(at 128.905 76.835 0)
			(effects
				(font
					(size 1.27 1.27)
				)
				(hide yes)
			)
		)
		(property "Value" "PWR_FLAG"
			(at 128.905 75.1642 0)
			(effects
				(font
					(size 1.27 1.27)
				)
			)
		)
		(property "Footprint" ""
			(at 128.905 78.74 0)
			(effects
				(font
					(size 1.27 1.27)
				)
				(hide yes)
			)
		)
		(property "Datasheet" ""
			(at 128.905 78.74 0)
			(effects
				(font
					(size 1.27 1.27)
				)
				(hide yes)
			)
		)
		(property "Description" ""
			(at 128.905 78.74 0)
			(effects
				(font
					(size 1.27 1.27)
				)
			)
		)
		(pin "1"
		)
		(instances
			(project "k410t-devboard"
				(path ""
					(reference "#FLG01")
					(unit 1)
				)
			)
		)
	)
	(symbol
		(lib_id "antmicropower:GND")
		(at 313.69 212.09 0)
		(unit 1)
		(exclude_from_sim no)
		(in_bom yes)
		(on_board yes)
		(dnp no)
		(fields_autoplaced yes)
		(property "Reference" "#PWR0111"
			(at 313.69 218.44 0)
			(effects
				(font
					(size 1.27 1.27)
				)
				(hide yes)
			)
		)
		(property "Value" "GND"
			(at 313.69 215.9 0)
			(effects
				(font
					(size 1.27 1.27)
				)
			)
		)
		(property "Footprint" ""
			(at 322.58 219.71 0)
			(effects
				(font
					(size 1.27 1.27)
					(thickness 0.15)
				)
				(justify left bottom)
				(hide yes)
			)
		)
		(property "Datasheet" ""
			(at 322.58 224.79 0)
			(effects
				(font
					(size 1.27 1.27)
					(thickness 0.15)
				)
				(justify left bottom)
				(hide yes)
			)
		)
		(property "Description" ""
			(at 313.69 212.09 0)
			(effects
				(font
					(size 1.27 1.27)
				)
			)
		)
		(property "Author" "Antmicro"
			(at 322.58 219.71 0)
			(effects
				(font
					(size 1.27 1.27)
					(thickness 0.15)
				)
				(justify left bottom)
				(hide yes)
			)
		)
		(property "License" "Apache-2.0"
			(at 322.58 222.25 0)
			(effects
				(font
					(size 1.27 1.27)
					(thickness 0.15)
				)
				(justify left bottom)
				(hide yes)
			)
		)
		(pin "1"
		)
		(instances
			(project "k410t-devboard"
				(path ""
					(reference "#PWR0111")
					(unit 1)
				)
			)
		)
	)
	(symbol
		(lib_id "antmicroTransistorsFETsMOSFETsSingle:SI7613DN-T1-GE3")
		(at 339.09 91.44 90)
		(unit 1)
		(exclude_from_sim no)
		(in_bom yes)
		(on_board yes)
		(dnp no)
		(fields_autoplaced yes)
		(property "Reference" "Q6"
			(at 336.55 77.47 90)
			(effects
				(font
					(size 1.27 1.27)
				)
			)
		)
		(property "Value" "SI7613DN-T1-GE3"
			(at 336.55 78.74 90)
			(effects
				(font
					(size 1.27 1.27)
					(thickness 0.15)
				)
				(hide yes)
			)
		)
		(property "Footprint" "antmicro-footprints:Vishay_PowerPAK_1212-8_Single"
			(at 337.82 76.2 0)
			(effects
				(font
					(size 1.27 1.27)
					(thickness 0.15)
				)
				(justify left bottom)
				(hide yes)
			)
		)
		(property "Datasheet" "https://www.vishay.com/docs/64809/si7613dn.pdf"
			(at 340.36 76.2 0)
			(effects
				(font
					(size 1.27 1.27)
					(thickness 0.15)
				)
				(justify left bottom)
				(hide yes)
			)
		)
		(property "Description" ""
			(at 339.09 91.44 0)
			(effects
				(font
					(size 1.27 1.27)
				)
			)
		)
		(property "MPN" "SI7613DN-T1-GE3"
			(at 336.55 80.01 90)
			(effects
				(font
					(size 1.27 1.27)
					(thickness 0.15)
				)
			)
		)
		(property "Manufacturer" "Vishay"
			(at 346.71 76.2 0)
			(effects
				(font
					(size 1.27 1.27)
					(thickness 0.15)
				)
				(justify left bottom)
				(hide yes)
			)
		)
		(property "Author" "Antmicro"
			(at 349.25 76.2 0)
			(effects
				(font
					(size 1.27 1.27)
					(thickness 0.15)
				)
				(justify left bottom)
				(hide yes)
			)
		)
		(property "License" "Apache-2.0"
			(at 351.79 76.2 0)
			(effects
				(font
					(size 1.27 1.27)
					(thickness 0.15)
				)
				(justify left bottom)
				(hide yes)
			)
		)
		(pin "1"
		)
		(pin "2"
		)
		(pin "3"
		)
		(pin "4"
		)
		(pin "5"
		)
		(instances
			(project "k410t-devboard"
				(path ""
					(reference "Q6")
					(unit 1)
				)
			)
		)
	)
	(symbol
		(lib_id "antmicroTVSDiodes:ESDA25P35-1U1M")
		(at 90.17 91.44 90)
		(mirror x)
		(unit 1)
		(exclude_from_sim no)
		(in_bom yes)
		(on_board yes)
		(dnp no)
		(property "Reference" "D8"
			(at 87.63 95.5675 90)
			(effects
				(font
					(size 1.27 1.27)
				)
				(justify left)
			)
		)
		(property "Value" "ESDA25P35-1U1M"
			(at 86.995 93.0276 90)
			(effects
				(font
					(size 1.27 1.27)
					(thickness 0.15)
				)
				(justify left)
				(hide yes)
			)
		)
		(property "Footprint" "antmicro-footprints:QFN-2L_1.6x1x0.55mm"
			(at 100.33 115.57 0)
			(effects
				(font
					(size 1.27 1.27)
					(thickness 0.15)
				)
				(justify left bottom)
				(hide yes)
			)
		)
		(property "Datasheet" "https://www.st.com/resource/en/datasheet/esda25p35-1u1m.pdf"
			(at 102.87 115.57 0)
			(effects
				(font
					(size 1.27 1.27)
					(thickness 0.15)
				)
				(justify left bottom)
				(hide yes)
			)
		)
		(property "Description" ""
			(at 90.17 91.44 0)
			(effects
				(font
					(size 1.27 1.27)
				)
			)
		)
		(property "MPN" "ESDA25P35-1U1M"
			(at 87.63 93.0275 90)
			(effects
				(font
					(size 1.27 1.27)
					(thickness 0.15)
				)
				(justify left)
			)
		)
		(property "Manufacturer" "STMicroelectronics"
			(at 107.95 115.57 0)
			(effects
				(font
					(size 1.27 1.27)
					(thickness 0.15)
				)
				(justify left bottom)
				(hide yes)
			)
		)
		(property "Author" "Antmicro"
			(at 110.49 115.57 0)
			(effects
				(font
					(size 1.27 1.27)
					(thickness 0.15)
				)
				(justify left bottom)
				(hide yes)
			)
		)
		(property "License" "Apache-2.0"
			(at 113.03 115.57 0)
			(effects
				(font
					(size 1.27 1.27)
					(thickness 0.15)
				)
				(justify left bottom)
				(hide yes)
			)
		)
		(property "Public" "False"
			(at 107.95 111.76 0)
			(effects
				(font
					(size 1.27 1.27)
				)
				(justify left bottom)
				(hide yes)
			)
		)
		(pin "1"
		)
		(pin "2"
		)
		(instances
			(project "k410t-devboard"
				(path ""
					(reference "D8")
					(unit 1)
				)
			)
		)
	)
	(symbol
		(lib_id "antmicropower:GND")
		(at 151.13 153.67 0)
		(mirror y)
		(unit 1)
		(exclude_from_sim no)
		(in_bom yes)
		(on_board yes)
		(dnp no)
		(property "Reference" "#PWR092"
			(at 151.13 160.02 0)
			(effects
				(font
					(size 1.27 1.27)
				)
				(hide yes)
			)
		)
		(property "Value" "GND"
			(at 151.13 157.48 0)
			(effects
				(font
					(size 1.27 1.27)
				)
			)
		)
		(property "Footprint" ""
			(at 142.24 161.29 0)
			(effects
				(font
					(size 1.27 1.27)
					(thickness 0.15)
				)
				(justify left bottom)
				(hide yes)
			)
		)
		(property "Datasheet" ""
			(at 142.24 166.37 0)
			(effects
				(font
					(size 1.27 1.27)
					(thickness 0.15)
				)
				(justify left bottom)
				(hide yes)
			)
		)
		(property "Description" ""
			(at 151.13 153.67 0)
			(effects
				(font
					(size 1.27 1.27)
				)
			)
		)
		(property "Author" "Antmicro"
			(at 142.24 161.29 0)
			(effects
				(font
					(size 1.27 1.27)
					(thickness 0.15)
				)
				(justify left bottom)
				(hide yes)
			)
		)
		(property "License" "Apache-2.0"
			(at 142.24 163.83 0)
			(effects
				(font
					(size 1.27 1.27)
					(thickness 0.15)
				)
				(justify left bottom)
				(hide yes)
			)
		)
		(pin "1"
		)
		(instances
			(project "k410t-devboard"
				(path ""
					(reference "#PWR092")
					(unit 1)
				)
			)
		)
	)
	(symbol
		(lib_id "antmicropower:GNDD")
		(at 204.47 262.89 0)
		(unit 1)
		(exclude_from_sim no)
		(in_bom yes)
		(on_board yes)
		(dnp no)
		(property "Reference" "#PWR0104"
			(at 204.47 269.24 0)
			(effects
				(font
					(size 1.27 1.27)
				)
				(hide yes)
			)
		)
		(property "Value" "GNDD"
			(at 204.47 266.7 0)
			(effects
				(font
					(size 1.27 1.27)
				)
			)
		)
		(property "Footprint" ""
			(at 204.47 262.89 0)
			(effects
				(font
					(size 1.27 1.27)
				)
				(hide yes)
			)
		)
		(property "Datasheet" ""
			(at 204.47 262.89 0)
			(effects
				(font
					(size 1.27 1.27)
				)
				(hide yes)
			)
		)
		(property "Description" ""
			(at 204.47 262.89 0)
			(effects
				(font
					(size 1.27 1.27)
				)
			)
		)
		(property "Author" "Antmicro"
			(at 219.71 270.51 0)
			(effects
				(font
					(size 1.27 1.27)
					(thickness 0.15)
				)
				(justify left bottom)
				(hide yes)
			)
		)
		(property "License" "Apache-2.0"
			(at 219.71 273.05 0)
			(effects
				(font
					(size 1.27 1.27)
					(thickness 0.15)
				)
				(justify left bottom)
				(hide yes)
			)
		)
		(pin "1"
		)
		(instances
			(project "k410t-devboard"
				(path ""
					(reference "#PWR0104")
					(unit 1)
				)
			)
		)
	)
	(symbol
		(lib_id "antmicroCapacitorsmisc:C_100n_100V_0805")
		(at 125.73 245.11 90)
		(unit 1)
		(exclude_from_sim no)
		(in_bom yes)
		(on_board yes)
		(dnp no)
		(fields_autoplaced yes)
		(property "Reference" "C194"
			(at 128.27 240.0236 90)
			(effects
				(font
					(size 1.27 1.27)
				)
				(justify right)
			)
		)
		(property "Value" "C_100n_100V_0805"
			(at 129.54 245.11 0)
			(effects
				(font
					(size 1.27 1.27)
				)
				(hide yes)
			)
		)
		(property "Footprint" "antmicro-footprints:C_0805_2012Metric"
			(at 120.65 240.03 0)
			(effects
				(font
					(size 1.27 1.27)
				)
				(justify left)
				(hide yes)
			)
		)
		(property "Datasheet" "https://product.samsungsem.com/mlcc/CL21B104KCFNNN.do"
			(at 125.73 245.11 0)
			(effects
				(font
					(size 1.27 1.27)
				)
				(hide yes)
			)
		)
		(property "Description" ""
			(at 125.73 245.11 0)
			(effects
				(font
					(size 1.27 1.27)
				)
			)
		)
		(property "Manufacturer" "Samsung Electro-Mechanics"
			(at 115.57 240.03 0)
			(effects
				(font
					(size 1.27 1.27)
				)
				(justify left)
				(hide yes)
			)
		)
		(property "MPN" "CL21B104KCFNNNE"
			(at 118.11 240.03 0)
			(effects
				(font
					(size 1.27 1.27)
				)
				(justify left)
				(hide yes)
			)
		)
		(property "Val" "100n"
			(at 128.27 242.5636 90)
			(effects
				(font
					(size 1.27 1.27)
				)
				(justify right)
			)
		)
		(property "License" "Apache-2.0"
			(at 148.59 224.79 0)
			(effects
				(font
					(size 1.27 1.27)
					(thickness 0.15)
				)
				(justify left bottom)
				(hide yes)
			)
		)
		(property "Author" "Antmicro"
			(at 151.13 224.79 0)
			(effects
				(font
					(size 1.27 1.27)
					(thickness 0.15)
				)
				(justify left bottom)
				(hide yes)
			)
		)
		(property "Voltage" "100V"
			(at 128.27 245.1036 90)
			(effects
				(font
					(size 1.27 1.27)
				)
				(justify right)
			)
		)
		(property "Dielectric" "X7R"
			(at 156.21 224.79 0)
			(effects
				(font
					(size 1.27 1.27)
				)
				(justify left bottom)
				(hide yes)
			)
		)
		(pin "1"
		)
		(pin "2"
		)
		(instances
			(project "k410t-devboard"
				(path ""
					(reference "C194")
					(unit 1)
				)
			)
		)
	)
	(symbol
		(lib_id "antmicroTVSDiodes:ESDA25P35-1U1M")
		(at 182.88 87.63 90)
		(mirror x)
		(unit 1)
		(exclude_from_sim no)
		(in_bom yes)
		(on_board yes)
		(dnp no)
		(property "Reference" "D14"
			(at 185.42 91.7575 90)
			(effects
				(font
					(size 1.27 1.27)
				)
				(justify right)
			)
		)
		(property "Value" "ESDA25P35-1U1M"
			(at 185.42 89.2176 90)
			(effects
				(font
					(size 1.27 1.27)
					(thickness 0.15)
				)
				(justify right)
				(hide yes)
			)
		)
		(property "Footprint" "antmicro-footprints:QFN-2L_1.6x1x0.55mm"
			(at 193.04 111.76 0)
			(effects
				(font
					(size 1.27 1.27)
					(thickness 0.15)
				)
				(justify left bottom)
				(hide yes)
			)
		)
		(property "Datasheet" "https://www.st.com/resource/en/datasheet/esda25p35-1u1m.pdf"
			(at 195.58 111.76 0)
			(effects
				(font
					(size 1.27 1.27)
					(thickness 0.15)
				)
				(justify left bottom)
				(hide yes)
			)
		)
		(property "Description" ""
			(at 182.88 87.63 0)
			(effects
				(font
					(size 1.27 1.27)
				)
			)
		)
		(property "MPN" "ESDA25P35-1U1M"
			(at 185.42 89.2175 90)
			(effects
				(font
					(size 1.27 1.27)
					(thickness 0.15)
				)
				(justify right)
			)
		)
		(property "Manufacturer" "STMicroelectronics"
			(at 200.66 111.76 0)
			(effects
				(font
					(size 1.27 1.27)
					(thickness 0.15)
				)
				(justify left bottom)
				(hide yes)
			)
		)
		(property "Author" "Antmicro"
			(at 203.2 111.76 0)
			(effects
				(font
					(size 1.27 1.27)
					(thickness 0.15)
				)
				(justify left bottom)
				(hide yes)
			)
		)
		(property "License" "Apache-2.0"
			(at 205.74 111.76 0)
			(effects
				(font
					(size 1.27 1.27)
					(thickness 0.15)
				)
				(justify left bottom)
				(hide yes)
			)
		)
		(property "Public" "False"
			(at 200.66 107.95 0)
			(effects
				(font
					(size 1.27 1.27)
				)
				(justify left bottom)
				(hide yes)
			)
		)
		(pin "1"
		)
		(pin "2"
		)
		(instances
			(project "k410t-devboard"
				(path ""
					(reference "D14")
					(unit 1)
				)
			)
		)
	)
	(symbol
		(lib_id "antmicroResistorsmisc:R_1k3_1206")
		(at 125.73 259.08 0)
		(unit 1)
		(exclude_from_sim no)
		(in_bom yes)
		(on_board yes)
		(dnp no)
		(fields_autoplaced yes)
		(property "Reference" "R47"
			(at 133.35 257.81 0)
			(effects
				(font
					(size 1.27 1.27)
				)
			)
		)
		(property "Value" "R_1k3_1206"
			(at 125.73 262.89 0)
			(effects
				(font
					(size 1.524 1.524)
				)
				(hide yes)
			)
		)
		(property "Footprint" "antmicro-footprints:R_1206_3216Metric"
			(at 130.81 254 0)
			(effects
				(font
					(size 1.524 1.524)
				)
				(justify left)
				(hide yes)
			)
		)
		(property "Datasheet" "https://www.bourns.com/docs/product-datasheets/cr.pdf"
			(at 125.73 259.08 0)
			(effects
				(font
					(size 1.27 1.27)
				)
				(hide yes)
			)
		)
		(property "Description" ""
			(at 125.73 259.08 0)
			(effects
				(font
					(size 1.27 1.27)
				)
			)
		)
		(property "Manufacturer" "Bourns"
			(at 130.81 248.92 0)
			(effects
				(font
					(size 1.524 1.524)
				)
				(justify left)
				(hide yes)
			)
		)
		(property "MPN" "CR1206-JW-132ELF"
			(at 130.81 251.46 0)
			(effects
				(font
					(size 1.524 1.524)
				)
				(justify left)
				(hide yes)
			)
		)
		(property "Val" "1k3"
			(at 123.825 257.81 0)
			(effects
				(font
					(size 1.27 1.27)
				)
			)
		)
		(property "License" "Apache-2.0"
			(at 146.05 284.48 0)
			(effects
				(font
					(size 1.27 1.27)
					(thickness 0.15)
				)
				(justify left bottom)
				(hide yes)
			)
		)
		(property "Author" "Antmicro"
			(at 146.05 287.02 0)
			(effects
				(font
					(size 1.27 1.27)
					(thickness 0.15)
				)
				(justify left bottom)
				(hide yes)
			)
		)
		(property "Tolerance" "1%"
			(at 146.05 269.24 0)
			(effects
				(font
					(size 1.27 1.27)
				)
				(justify left bottom)
				(hide yes)
			)
		)
		(pin "1"
		)
		(pin "2"
		)
		(instances
			(project "k410t-devboard"
				(path ""
					(reference "R47")
					(unit 1)
				)
			)
		)
	)
	(symbol
		(lib_id "antmicropower:GNDD")
		(at 137.16 208.28 0)
		(unit 1)
		(exclude_from_sim no)
		(in_bom yes)
		(on_board yes)
		(dnp no)
		(property "Reference" "#PWR095"
			(at 137.16 214.63 0)
			(effects
				(font
					(size 1.27 1.27)
				)
				(hide yes)
			)
		)
		(property "Value" "GNDD"
			(at 137.16 212.09 0)
			(effects
				(font
					(size 1.27 1.27)
				)
			)
		)
		(property "Footprint" ""
			(at 137.16 208.28 0)
			(effects
				(font
					(size 1.27 1.27)
				)
				(hide yes)
			)
		)
		(property "Datasheet" ""
			(at 137.16 208.28 0)
			(effects
				(font
					(size 1.27 1.27)
				)
				(hide yes)
			)
		)
		(property "Description" ""
			(at 137.16 208.28 0)
			(effects
				(font
					(size 1.27 1.27)
				)
			)
		)
		(property "Author" "Antmicro"
			(at 152.4 215.9 0)
			(effects
				(font
					(size 1.27 1.27)
					(thickness 0.15)
				)
				(justify left bottom)
				(hide yes)
			)
		)
		(property "License" "Apache-2.0"
			(at 152.4 218.44 0)
			(effects
				(font
					(size 1.27 1.27)
					(thickness 0.15)
				)
				(justify left bottom)
				(hide yes)
			)
		)
		(pin "1"
		)
		(instances
			(project "k410t-devboard"
				(path ""
					(reference "#PWR095")
					(unit 1)
				)
			)
		)
	)
	(symbol
		(lib_id "antmicroCapacitorsmisc:C_47u_16V_1206")
		(at 209.55 198.12 90)
		(unit 1)
		(exclude_from_sim no)
		(in_bom yes)
		(on_board yes)
		(dnp no)
		(property "Reference" "C200"
			(at 209.55 193.04 90)
			(effects
				(font
					(size 1.27 1.27)
				)
				(justify right)
			)
		)
		(property "Value" "C_47u_16V_1206"
			(at 219.71 177.8 0)
			(effects
				(font
					(size 1.27 1.27)
					(thickness 0.15)
				)
				(justify left bottom)
				(hide yes)
			)
		)
		(property "Footprint" "antmicro-footprints:C_1206_3216Metric"
			(at 222.25 177.8 0)
			(effects
				(font
					(size 1.27 1.27)
					(thickness 0.15)
				)
				(justify left bottom)
				(hide yes)
			)
		)
		(property "Datasheet" "https://product.tdk.com/en/search/capacitor/ceramic/mlcc/info?part_no=C3216X5R1C476M160AB"
			(at 224.79 177.8 0)
			(effects
				(font
					(size 1.27 1.27)
					(thickness 0.15)
				)
				(justify left bottom)
				(hide yes)
			)
		)
		(property "Description" ""
			(at 209.55 198.12 0)
			(effects
				(font
					(size 1.27 1.27)
				)
			)
		)
		(property "Manufacturer" "TDK"
			(at 229.87 177.8 0)
			(effects
				(font
					(size 1.27 1.27)
					(thickness 0.15)
				)
				(justify left bottom)
				(hide yes)
			)
		)
		(property "MPN" "C3216X5R1C476M160AB"
			(at 227.33 177.8 0)
			(effects
				(font
					(size 1.27 1.27)
					(thickness 0.15)
				)
				(justify left bottom)
				(hide yes)
			)
		)
		(property "Val" "47u"
			(at 209.55 198.12 90)
			(effects
				(font
					(size 1.27 1.27)
					(thickness 0.15)
				)
				(justify right)
			)
		)
		(property "License" "Apache-2.0"
			(at 232.41 177.8 0)
			(effects
				(font
					(size 1.27 1.27)
					(thickness 0.15)
				)
				(justify left bottom)
				(hide yes)
			)
		)
		(property "Author" "Antmicro"
			(at 234.95 177.8 0)
			(effects
				(font
					(size 1.27 1.27)
					(thickness 0.15)
				)
				(justify left bottom)
				(hide yes)
			)
		)
		(property "Voltage" "16V"
			(at 209.55 200.66 90)
			(effects
				(font
					(size 1.27 1.27)
				)
				(justify right)
			)
		)
		(property "Dielectric" "X5R"
			(at 240.03 177.8 0)
			(effects
				(font
					(size 1.27 1.27)
				)
				(justify left bottom)
				(hide yes)
			)
		)
		(pin "1"
		)
		(pin "2"
		)
		(instances
			(project "k410t-devboard"
				(path ""
					(reference "C200")
					(unit 1)
				)
			)
		)
	)
	(symbol
		(lib_id "antmicropower:GND")
		(at 170.18 153.67 0)
		(mirror y)
		(unit 1)
		(exclude_from_sim no)
		(in_bom yes)
		(on_board yes)
		(dnp no)
		(property "Reference" "#PWR099"
			(at 170.18 160.02 0)
			(effects
				(font
					(size 1.27 1.27)
				)
				(hide yes)
			)
		)
		(property "Value" "GND"
			(at 170.18 157.48 0)
			(effects
				(font
					(size 1.27 1.27)
				)
			)
		)
		(property "Footprint" ""
			(at 161.29 161.29 0)
			(effects
				(font
					(size 1.27 1.27)
					(thickness 0.15)
				)
				(justify left bottom)
				(hide yes)
			)
		)
		(property "Datasheet" ""
			(at 161.29 166.37 0)
			(effects
				(font
					(size 1.27 1.27)
					(thickness 0.15)
				)
				(justify left bottom)
				(hide yes)
			)
		)
		(property "Description" ""
			(at 170.18 153.67 0)
			(effects
				(font
					(size 1.27 1.27)
				)
			)
		)
		(property "Author" "Antmicro"
			(at 161.29 161.29 0)
			(effects
				(font
					(size 1.27 1.27)
					(thickness 0.15)
				)
				(justify left bottom)
				(hide yes)
			)
		)
		(property "License" "Apache-2.0"
			(at 161.29 163.83 0)
			(effects
				(font
					(size 1.27 1.27)
					(thickness 0.15)
				)
				(justify left bottom)
				(hide yes)
			)
		)
		(pin "1"
		)
		(instances
			(project "k410t-devboard"
				(path ""
					(reference "#PWR099")
					(unit 1)
				)
			)
		)
	)
	(symbol
		(lib_id "antmicroTVSDiodes:CD-MMBL110S")
		(at 53.34 251.46 0)
		(unit 1)
		(exclude_from_sim no)
		(in_bom no)
		(on_board yes)
		(dnp yes)
		(fields_autoplaced yes)
		(property "Reference" "D7"
			(at 62.23 245.11 0)
			(effects
				(font
					(size 1.27 1.27)
				)
			)
		)
		(property "Value" "CD-MMBL110S"
			(at 62.23 247.65 0)
			(effects
				(font
					(size 1.27 1.27)
					(thickness 0.15)
				)
				(hide yes)
			)
		)
		(property "Footprint" "antmicro-footprints:DFN3538"
			(at 85.09 261.62 0)
			(effects
				(font
					(size 1.27 1.27)
					(thickness 0.15)
				)
				(justify left bottom)
				(hide yes)
			)
		)
		(property "Datasheet" "https://www.bourns.com/docs/product-datasheets/CD-MMBL110S.pdf"
			(at 85.09 264.16 0)
			(effects
				(font
					(size 1.27 1.27)
					(thickness 0.15)
				)
				(justify left bottom)
				(hide yes)
			)
		)
		(property "Description" ""
			(at 53.34 251.46 0)
			(effects
				(font
					(size 1.27 1.27)
				)
			)
		)
		(property "MPN" "CD-MMBL110S"
			(at 62.23 247.65 0)
			(effects
				(font
					(size 1.27 1.27)
					(thickness 0.15)
				)
			)
		)
		(property "Manufacturer" "Bourns"
			(at 85.09 269.24 0)
			(effects
				(font
					(size 1.27 1.27)
					(thickness 0.15)
				)
				(justify left bottom)
				(hide yes)
			)
		)
		(property "Author" "Antmicro"
			(at 85.09 271.78 0)
			(effects
				(font
					(size 1.27 1.27)
					(thickness 0.15)
				)
				(justify left bottom)
				(hide yes)
			)
		)
		(property "License" "Apache-2.0"
			(at 85.09 274.32 0)
			(effects
				(font
					(size 1.27 1.27)
					(thickness 0.15)
				)
				(justify left bottom)
				(hide yes)
			)
		)
		(property "DNP" "DNP"
			(at 53.34 251.46 0)
			(effects
				(font
					(size 1.27 1.27)
				)
				(hide yes)
			)
		)
		(pin "1"
		)
		(pin "2"
		)
		(pin "3"
		)
		(pin "4"
		)
		(instances
			(project "k410t-devboard"
				(path ""
					(reference "D7")
					(unit 1)
				)
			)
		)
	)
	(symbol
		(lib_id "antmicroCapacitors0402:C_100n_0402")
		(at 303.53 101.6 90)
		(unit 1)
		(exclude_from_sim no)
		(in_bom yes)
		(on_board yes)
		(dnp no)
		(fields_autoplaced yes)
		(property "Reference" "C204"
			(at 306.07 97.7835 90)
			(effects
				(font
					(size 1.27 1.27)
				)
				(justify right)
			)
		)
		(property "Value" "C_100n_0402"
			(at 313.69 81.28 0)
			(effects
				(font
					(size 1.27 1.27)
					(thickness 0.15)
				)
				(justify left bottom)
				(hide yes)
			)
		)
		(property "Footprint" "antmicro-footprints:C_0402_1005Metric"
			(at 316.23 81.28 0)
			(effects
				(font
					(size 1.27 1.27)
					(thickness 0.15)
				)
				(justify left bottom)
				(hide yes)
			)
		)
		(property "Datasheet" "https://www.murata.com/products/productdetail?partno=GRM155R61H104KE14%23"
			(at 318.77 81.28 0)
			(effects
				(font
					(size 1.27 1.27)
					(thickness 0.15)
				)
				(justify left bottom)
				(hide yes)
			)
		)
		(property "Description" ""
			(at 303.53 101.6 0)
			(effects
				(font
					(size 1.27 1.27)
				)
			)
		)
		(property "Manufacturer" "Murata"
			(at 323.85 81.28 0)
			(effects
				(font
					(size 1.27 1.27)
					(thickness 0.15)
				)
				(justify left bottom)
				(hide yes)
			)
		)
		(property "MPN" "GRM155R61H104KE14D"
			(at 321.31 81.28 0)
			(effects
				(font
					(size 1.27 1.27)
					(thickness 0.15)
				)
				(justify left bottom)
				(hide yes)
			)
		)
		(property "Val" "100n"
			(at 306.07 100.3235 90)
			(effects
				(font
					(size 1.27 1.27)
					(thickness 0.15)
				)
				(justify right)
			)
		)
		(property "License" "Apache-2.0"
			(at 326.39 81.28 0)
			(effects
				(font
					(size 1.27 1.27)
					(thickness 0.15)
				)
				(justify left bottom)
				(hide yes)
			)
		)
		(property "Author" "Antmicro"
			(at 328.93 81.28 0)
			(effects
				(font
					(size 1.27 1.27)
					(thickness 0.15)
				)
				(justify left bottom)
				(hide yes)
			)
		)
		(property "Voltage" "50V"
			(at 331.47 81.28 0)
			(effects
				(font
					(size 1.27 1.27)
				)
				(justify left bottom)
				(hide yes)
			)
		)
		(property "Dielectric" "X5R"
			(at 334.01 81.28 0)
			(effects
				(font
					(size 1.27 1.27)
				)
				(justify left bottom)
				(hide yes)
			)
		)
		(pin "1"
		)
		(pin "2"
		)
		(instances
			(project "k410t-devboard"
				(path ""
					(reference "C204")
					(unit 1)
				)
			)
		)
	)
	(symbol
		(lib_id "antmicroResistors0402:R_1k_0402")
		(at 161.29 100.33 270)
		(unit 1)
		(exclude_from_sim no)
		(in_bom yes)
		(on_board yes)
		(dnp no)
		(property "Reference" "R56"
			(at 162.56 101.6 90)
			(effects
				(font
					(size 1.27 1.27)
				)
				(justify left)
			)
		)
		(property "Value" "R_1k_0402"
			(at 148.59 120.65 0)
			(effects
				(font
					(size 1.27 1.27)
					(thickness 0.15)
				)
				(justify left bottom)
				(hide yes)
			)
		)
		(property "Footprint" "antmicro-footprints:R_0402_1005Metric"
			(at 146.05 120.65 0)
			(effects
				(font
					(size 1.27 1.27)
					(thickness 0.15)
				)
				(justify left bottom)
				(hide yes)
			)
		)
		(property "Datasheet" "https://www.bourns.com/docs/product-datasheets/cr.pdf"
			(at 143.51 120.65 0)
			(effects
				(font
					(size 1.27 1.27)
					(thickness 0.15)
				)
				(justify left bottom)
				(hide yes)
			)
		)
		(property "Description" ""
			(at 161.29 100.33 0)
			(effects
				(font
					(size 1.27 1.27)
				)
			)
		)
		(property "Manufacturer" "Bourns"
			(at 138.43 120.65 0)
			(effects
				(font
					(size 1.27 1.27)
					(thickness 0.15)
				)
				(justify left bottom)
				(hide yes)
			)
		)
		(property "MPN" "CR0402-FX-1001GLF"
			(at 140.97 120.65 0)
			(effects
				(font
					(size 1.27 1.27)
					(thickness 0.15)
				)
				(justify left bottom)
				(hide yes)
			)
		)
		(property "Val" "1k"
			(at 162.56 104.14 90)
			(effects
				(font
					(size 1.27 1.27)
					(thickness 0.15)
				)
				(justify left)
			)
		)
		(property "License" "Apache-2.0"
			(at 135.89 120.65 0)
			(effects
				(font
					(size 1.27 1.27)
					(thickness 0.15)
				)
				(justify left bottom)
				(hide yes)
			)
		)
		(property "Author" "Antmicro"
			(at 133.35 120.65 0)
			(effects
				(font
					(size 1.27 1.27)
					(thickness 0.15)
				)
				(justify left bottom)
				(hide yes)
			)
		)
		(property "Tolerance" "1%"
			(at 151.13 120.65 0)
			(effects
				(font
					(size 1.27 1.27)
				)
				(justify left bottom)
				(hide yes)
			)
		)
		(pin "1"
		)
		(pin "2"
		)
		(instances
			(project "k410t-devboard"
				(path ""
					(reference "R56")
					(unit 1)
				)
			)
		)
	)
	(symbol
		(lib_id "antmicroResistors0402:R_0R_0402")
		(at 199.39 198.12 0)
		(unit 1)
		(exclude_from_sim no)
		(in_bom yes)
		(on_board yes)
		(dnp no)
		(property "Reference" "R62"
			(at 201.93 195.58 0)
			(effects
				(font
					(size 1.27 1.27)
				)
			)
		)
		(property "Value" "R_0R_0402"
			(at 219.71 210.82 0)
			(effects
				(font
					(size 1.27 1.27)
					(thickness 0.15)
				)
				(justify left bottom)
				(hide yes)
			)
		)
		(property "Footprint" "antmicro-footprints:R_0402_1005Metric"
			(at 219.71 213.36 0)
			(effects
				(font
					(size 1.27 1.27)
					(thickness 0.15)
				)
				(justify left bottom)
				(hide yes)
			)
		)
		(property "Datasheet" "https://industrial.panasonic.com/cdbs/www-data/pdf/RDA0000/AOA0000C301.pdf"
			(at 219.71 215.9 0)
			(effects
				(font
					(size 1.27 1.27)
					(thickness 0.15)
				)
				(justify left bottom)
				(hide yes)
			)
		)
		(property "Description" ""
			(at 199.39 198.12 0)
			(effects
				(font
					(size 1.27 1.27)
				)
			)
		)
		(property "Manufacturer" "Panasonic"
			(at 219.71 220.98 0)
			(effects
				(font
					(size 1.27 1.27)
					(thickness 0.15)
				)
				(justify left bottom)
				(hide yes)
			)
		)
		(property "MPN" "ERJ2GE0R00X"
			(at 219.71 218.44 0)
			(effects
				(font
					(size 1.27 1.27)
					(thickness 0.15)
				)
				(justify left bottom)
				(hide yes)
			)
		)
		(property "Val" "0R"
			(at 201.93 200.66 0)
			(effects
				(font
					(size 1.27 1.27)
					(thickness 0.15)
				)
			)
		)
		(property "License" "Apache-2.0"
			(at 219.71 223.52 0)
			(effects
				(font
					(size 1.27 1.27)
					(thickness 0.15)
				)
				(justify left bottom)
				(hide yes)
			)
		)
		(property "Author" "Antmicro"
			(at 219.71 226.06 0)
			(effects
				(font
					(size 1.27 1.27)
					(thickness 0.15)
				)
				(justify left bottom)
				(hide yes)
			)
		)
		(property "Tolerance" "~"
			(at 219.71 208.28 0)
			(effects
				(font
					(size 1.27 1.27)
				)
				(justify left bottom)
				(hide yes)
			)
		)
		(property "Current" "1A"
			(at 201.93 194.31 0)
			(effects
				(font
					(size 1.27 1.27)
					(thickness 0.15)
				)
				(hide yes)
			)
		)
		(pin "1"
		)
		(pin "2"
		)
		(instances
			(project "k410t-devboard"
				(path ""
					(reference "R62")
					(unit 1)
				)
			)
		)
	)
	(symbol
		(lib_id "antmicroResistors0402:R_47k_0402")
		(at 115.57 198.12 90)
		(unit 1)
		(exclude_from_sim no)
		(in_bom yes)
		(on_board yes)
		(dnp no)
		(fields_autoplaced yes)
		(property "Reference" "R46"
			(at 118.11 194.3099 90)
			(effects
				(font
					(size 1.27 1.27)
				)
				(justify right)
			)
		)
		(property "Value" "R_47k_0402"
			(at 128.27 177.8 0)
			(effects
				(font
					(size 1.27 1.27)
					(thickness 0.15)
				)
				(justify left bottom)
				(hide yes)
			)
		)
		(property "Footprint" "antmicro-footprints:R_0402_1005Metric"
			(at 130.81 177.8 0)
			(effects
				(font
					(size 1.27 1.27)
					(thickness 0.15)
				)
				(justify left bottom)
				(hide yes)
			)
		)
		(property "Datasheet" "https://www.bourns.com/docs/product-datasheets/cr.pdf"
			(at 133.35 177.8 0)
			(effects
				(font
					(size 1.27 1.27)
					(thickness 0.15)
				)
				(justify left bottom)
				(hide yes)
			)
		)
		(property "Description" ""
			(at 115.57 198.12 0)
			(effects
				(font
					(size 1.27 1.27)
				)
			)
		)
		(property "Manufacturer" "Bourns"
			(at 138.43 177.8 0)
			(effects
				(font
					(size 1.27 1.27)
					(thickness 0.15)
				)
				(justify left bottom)
				(hide yes)
			)
		)
		(property "MPN" "CR0402-FX-4702GLF"
			(at 135.89 177.8 0)
			(effects
				(font
					(size 1.27 1.27)
					(thickness 0.15)
				)
				(justify left bottom)
				(hide yes)
			)
		)
		(property "Val" "47k"
			(at 118.11 196.8499 90)
			(effects
				(font
					(size 1.27 1.27)
					(thickness 0.15)
				)
				(justify right)
			)
		)
		(property "License" "Apache-2.0"
			(at 140.97 177.8 0)
			(effects
				(font
					(size 1.27 1.27)
					(thickness 0.15)
				)
				(justify left bottom)
				(hide yes)
			)
		)
		(property "Author" "Antmicro"
			(at 143.51 177.8 0)
			(effects
				(font
					(size 1.27 1.27)
					(thickness 0.15)
				)
				(justify left bottom)
				(hide yes)
			)
		)
		(property "Tolerance" "1%"
			(at 125.73 177.8 0)
			(effects
				(font
					(size 1.27 1.27)
				)
				(justify left bottom)
				(hide yes)
			)
		)
		(pin "1"
		)
		(pin "2"
		)
		(instances
			(project "k410t-devboard"
				(path ""
					(reference "R46")
					(unit 1)
				)
			)
		)
	)
	(symbol
		(lib_id "antmicroCapacitors0402:C_1u_0402")
		(at 160.02 147.32 90)
		(mirror x)
		(unit 1)
		(exclude_from_sim no)
		(in_bom yes)
		(on_board yes)
		(dnp no)
		(property "Reference" "C193"
			(at 160.655 147.955 90)
			(effects
				(font
					(size 1.27 1.27)
				)
				(justify right)
			)
		)
		(property "Value" "C_1u_0402"
			(at 170.18 167.64 0)
			(effects
				(font
					(size 1.27 1.27)
					(thickness 0.15)
				)
				(justify left bottom)
				(hide yes)
			)
		)
		(property "Footprint" "antmicro-footprints:C_0402_1005Metric"
			(at 172.72 167.64 0)
			(effects
				(font
					(size 1.27 1.27)
					(thickness 0.15)
				)
				(justify left bottom)
				(hide yes)
			)
		)
		(property "Datasheet" "https://product.tdk.com/en/search/capacitor/ceramic/mlcc/info?part_no=C1005X6S1A105K050BC"
			(at 175.26 167.64 0)
			(effects
				(font
					(size 1.27 1.27)
					(thickness 0.15)
				)
				(justify left bottom)
				(hide yes)
			)
		)
		(property "Description" ""
			(at 160.02 147.32 0)
			(effects
				(font
					(size 1.27 1.27)
				)
			)
		)
		(property "Manufacturer" "TDK"
			(at 180.34 167.64 0)
			(effects
				(font
					(size 1.27 1.27)
					(thickness 0.15)
				)
				(justify left bottom)
				(hide yes)
			)
		)
		(property "MPN" "C1005X6S1A105K050BC"
			(at 177.8 167.64 0)
			(effects
				(font
					(size 1.27 1.27)
					(thickness 0.15)
				)
				(justify left bottom)
				(hide yes)
			)
		)
		(property "Val" "1u"
			(at 160.655 151.765 90)
			(effects
				(font
					(size 1.27 1.27)
					(thickness 0.15)
				)
				(justify right)
			)
		)
		(property "License" "Apache-2.0"
			(at 182.88 167.64 0)
			(effects
				(font
					(size 1.27 1.27)
					(thickness 0.15)
				)
				(justify left bottom)
				(hide yes)
			)
		)
		(property "Author" "Antmicro"
			(at 185.42 167.64 0)
			(effects
				(font
					(size 1.27 1.27)
					(thickness 0.15)
				)
				(justify left bottom)
				(hide yes)
			)
		)
		(property "Voltage" ""
			(at 187.96 167.64 0)
			(effects
				(font
					(size 1.27 1.27)
				)
				(justify left bottom)
				(hide yes)
			)
		)
		(property "Dielectric" ""
			(at 190.5 167.64 0)
			(effects
				(font
					(size 1.27 1.27)
				)
				(justify left bottom)
				(hide yes)
			)
		)
		(pin "1"
		)
		(pin "2"
		)
		(instances
			(project "k410t-devboard"
				(path ""
					(reference "C193")
					(unit 1)
				)
			)
		)
	)
	(symbol
		(lib_id "antmicropower:GNDD")
		(at 115.57 208.28 0)
		(unit 1)
		(exclude_from_sim no)
		(in_bom yes)
		(on_board yes)
		(dnp no)
		(property "Reference" "#PWR093"
			(at 115.57 214.63 0)
			(effects
				(font
					(size 1.27 1.27)
				)
				(hide yes)
			)
		)
		(property "Value" "GNDD"
			(at 115.57 212.09 0)
			(effects
				(font
					(size 1.27 1.27)
				)
			)
		)
		(property "Footprint" ""
			(at 115.57 208.28 0)
			(effects
				(font
					(size 1.27 1.27)
				)
				(hide yes)
			)
		)
		(property "Datasheet" ""
			(at 115.57 208.28 0)
			(effects
				(font
					(size 1.27 1.27)
				)
				(hide yes)
			)
		)
		(property "Description" ""
			(at 115.57 208.28 0)
			(effects
				(font
					(size 1.27 1.27)
				)
			)
		)
		(property "Author" "Antmicro"
			(at 130.81 215.9 0)
			(effects
				(font
					(size 1.27 1.27)
					(thickness 0.15)
				)
				(justify left bottom)
				(hide yes)
			)
		)
		(property "License" "Apache-2.0"
			(at 130.81 218.44 0)
			(effects
				(font
					(size 1.27 1.27)
					(thickness 0.15)
				)
				(justify left bottom)
				(hide yes)
			)
		)
		(pin "1"
		)
		(instances
			(project "k410t-devboard"
				(path ""
					(reference "#PWR093")
					(unit 1)
				)
			)
		)
	)
	(symbol
		(lib_id "antmicroResistors0402:R_100R_0402")
		(at 142.875 96.52 0)
		(unit 1)
		(exclude_from_sim no)
		(in_bom yes)
		(on_board yes)
		(dnp no)
		(property "Reference" "R54"
			(at 145.415 93.98 0)
			(effects
				(font
					(size 1.27 1.27)
				)
			)
		)
		(property "Value" "R_100R_0402"
			(at 163.195 109.22 0)
			(effects
				(font
					(size 1.27 1.27)
					(thickness 0.15)
				)
				(justify left bottom)
				(hide yes)
			)
		)
		(property "Footprint" "antmicro-footprints:R_0402_1005Metric"
			(at 163.195 111.76 0)
			(effects
				(font
					(size 1.27 1.27)
					(thickness 0.15)
				)
				(justify left bottom)
				(hide yes)
			)
		)
		(property "Datasheet" "https://www.bourns.com/docs/product-datasheets/cr.pdf"
			(at 163.195 114.3 0)
			(effects
				(font
					(size 1.27 1.27)
					(thickness 0.15)
				)
				(justify left bottom)
				(hide yes)
			)
		)
		(property "Description" ""
			(at 142.875 96.52 0)
			(effects
				(font
					(size 1.27 1.27)
				)
			)
		)
		(property "Manufacturer" "Bourns"
			(at 163.195 119.38 0)
			(effects
				(font
					(size 1.27 1.27)
					(thickness 0.15)
				)
				(justify left bottom)
				(hide yes)
			)
		)
		(property "MPN" "CR0402-FX-1000GLF"
			(at 163.195 116.84 0)
			(effects
				(font
					(size 1.27 1.27)
					(thickness 0.15)
				)
				(justify left bottom)
				(hide yes)
			)
		)
		(property "Val" "100R"
			(at 145.415 99.06 0)
			(effects
				(font
					(size 1.27 1.27)
					(thickness 0.15)
				)
			)
		)
		(property "License" "Apache-2.0"
			(at 163.195 121.92 0)
			(effects
				(font
					(size 1.27 1.27)
					(thickness 0.15)
				)
				(justify left bottom)
				(hide yes)
			)
		)
		(property "Author" "Antmicro"
			(at 163.195 124.46 0)
			(effects
				(font
					(size 1.27 1.27)
					(thickness 0.15)
				)
				(justify left bottom)
				(hide yes)
			)
		)
		(property "Tolerance" "1%"
			(at 163.195 106.68 0)
			(effects
				(font
					(size 1.27 1.27)
				)
				(justify left bottom)
				(hide yes)
			)
		)
		(pin "1"
		)
		(pin "2"
		)
		(instances
			(project "k410t-devboard"
				(path ""
					(reference "R54")
					(unit 1)
				)
			)
		)
	)
	(symbol
		(lib_id "antmicroPMICORControllersIdealDiodes:LTC4412IS6")
		(at 314.96 200.66 0)
		(unit 1)
		(exclude_from_sim no)
		(in_bom yes)
		(on_board yes)
		(dnp no)
		(fields_autoplaced yes)
		(property "Reference" "U11"
			(at 323.85 193.04 0)
			(effects
				(font
					(size 1.27 1.27)
				)
			)
		)
		(property "Value" "LTC4412IS6"
			(at 323.85 213.36 0)
			(effects
				(font
					(size 1.27 1.27)
					(thickness 0.15)
				)
				(hide yes)
			)
		)
		(property "Footprint" "antmicro-footprints:SOT-23-6"
			(at 346.71 208.28 0)
			(effects
				(font
					(size 1.27 1.27)
					(thickness 0.15)
				)
				(justify left bottom)
				(hide yes)
			)
		)
		(property "Datasheet" "https://www.mouser.com/datasheet/2/308/NCV8187_D-1813214.pdf"
			(at 346.71 210.82 0)
			(effects
				(font
					(size 1.27 1.27)
					(thickness 0.15)
				)
				(justify left bottom)
				(hide yes)
			)
		)
		(property "Description" ""
			(at 314.96 200.66 0)
			(effects
				(font
					(size 1.27 1.27)
				)
			)
		)
		(property "MPN" "LTC4412IS6#TRMPBF"
			(at 323.85 195.58 0)
			(effects
				(font
					(size 1.27 1.27)
					(thickness 0.15)
				)
			)
		)
		(property "Manufacturer" "Analog Devices"
			(at 346.71 215.9 0)
			(effects
				(font
					(size 1.27 1.27)
					(thickness 0.15)
				)
				(justify left bottom)
				(hide yes)
			)
		)
		(property "Author" "Antmicro"
			(at 346.71 218.44 0)
			(effects
				(font
					(size 1.27 1.27)
					(thickness 0.15)
				)
				(justify left bottom)
				(hide yes)
			)
		)
		(property "License" "Apache-2.0"
			(at 346.71 220.98 0)
			(effects
				(font
					(size 1.27 1.27)
					(thickness 0.15)
				)
				(justify left bottom)
				(hide yes)
			)
		)
		(pin "1"
		)
		(pin "2"
		)
		(pin "3"
		)
		(pin "4"
		)
		(pin "5"
		)
		(pin "6"
		)
		(instances
			(project "k410t-devboard"
				(path ""
					(reference "U11")
					(unit 1)
				)
			)
		)
	)
	(symbol
		(lib_id "antmicroCapacitors0603:C_1u_25V_0603")
		(at 350.52 52.07 90)
		(unit 1)
		(exclude_from_sim no)
		(in_bom yes)
		(on_board yes)
		(dnp no)
		(fields_autoplaced yes)
		(property "Reference" "C206"
			(at 353.695 48.2535 90)
			(effects
				(font
					(size 1.27 1.27)
				)
				(justify right)
			)
		)
		(property "Value" "C_1u_25V_0603"
			(at 360.68 31.75 0)
			(effects
				(font
					(size 1.27 1.27)
					(thickness 0.15)
				)
				(justify left bottom)
				(hide yes)
			)
		)
		(property "Footprint" "antmicro-footprints:C_0603_1608Metric"
			(at 363.22 31.75 0)
			(effects
				(font
					(size 1.27 1.27)
					(thickness 0.15)
				)
				(justify left bottom)
				(hide yes)
			)
		)
		(property "Datasheet" "https://product.samsungsem.com/mlcc/CL10A105KA8NNN.do"
			(at 365.76 31.75 0)
			(effects
				(font
					(size 1.27 1.27)
					(thickness 0.15)
				)
				(justify left bottom)
				(hide yes)
			)
		)
		(property "Description" ""
			(at 350.52 52.07 0)
			(effects
				(font
					(size 1.27 1.27)
				)
			)
		)
		(property "Manufacturer" "Samsung Electro-Mechanics"
			(at 370.84 31.75 0)
			(effects
				(font
					(size 1.27 1.27)
					(thickness 0.15)
				)
				(justify left bottom)
				(hide yes)
			)
		)
		(property "MPN" "CL10A105KA8NNNC"
			(at 368.3 31.75 0)
			(effects
				(font
					(size 1.27 1.27)
					(thickness 0.15)
				)
				(justify left bottom)
				(hide yes)
			)
		)
		(property "Val" "1u"
			(at 353.695 50.7935 90)
			(effects
				(font
					(size 1.27 1.27)
					(thickness 0.15)
				)
				(justify right)
			)
		)
		(property "License" "Apache-2.0"
			(at 373.38 31.75 0)
			(effects
				(font
					(size 1.27 1.27)
					(thickness 0.15)
				)
				(justify left bottom)
				(hide yes)
			)
		)
		(property "Author" "Antmicro"
			(at 375.92 31.75 0)
			(effects
				(font
					(size 1.27 1.27)
					(thickness 0.15)
				)
				(justify left bottom)
				(hide yes)
			)
		)
		(property "Voltage" "25V"
			(at 378.46 31.75 0)
			(effects
				(font
					(size 1.27 1.27)
				)
				(justify left bottom)
				(hide yes)
			)
		)
		(property "Dielectric" ""
			(at 381 31.75 0)
			(effects
				(font
					(size 1.27 1.27)
				)
				(justify left bottom)
				(hide yes)
			)
		)
		(pin "1"
		)
		(pin "2"
		)
		(instances
			(project "k410t-devboard"
				(path ""
					(reference "C206")
					(unit 1)
				)
			)
		)
	)
	(symbol
		(lib_id "antmicroDiodesRectifiersSingle:PMEG3050EP,115")
		(at 334.01 177.8 0)
		(unit 1)
		(exclude_from_sim no)
		(in_bom no)
		(on_board yes)
		(dnp yes)
		(property "Reference" "D17"
			(at 336.8675 170.815 0)
			(effects
				(font
					(size 1.27 1.27)
				)
			)
		)
		(property "Value" "PMEG3050EP,115"
			(at 336.8675 173.355 0)
			(effects
				(font
					(size 1.27 1.27)
					(thickness 0.15)
				)
			)
		)
		(property "Footprint" "antmicro-footprints:Nexperia_SOD128"
			(at 355.6 187.96 0)
			(effects
				(font
					(size 1.27 1.27)
					(thickness 0.15)
				)
				(justify left bottom)
				(hide yes)
			)
		)
		(property "Datasheet" "https://www.mouser.com/datasheet/2/916/PMEG3050EP-2938519.pdf"
			(at 355.6 190.5 0)
			(effects
				(font
					(size 1.27 1.27)
					(thickness 0.15)
				)
				(justify left bottom)
				(hide yes)
			)
		)
		(property "Description" ""
			(at 334.01 177.8 0)
			(effects
				(font
					(size 1.27 1.27)
				)
			)
		)
		(property "MPN" "PMEG3050EP,115"
			(at 355.6 193.04 0)
			(effects
				(font
					(size 1.27 1.27)
					(thickness 0.15)
				)
				(justify left bottom)
				(hide yes)
			)
		)
		(property "Manufacturer" "Nexperia"
			(at 355.6 195.58 0)
			(effects
				(font
					(size 1.27 1.27)
					(thickness 0.15)
				)
				(justify left bottom)
				(hide yes)
			)
		)
		(property "Author" "Antmicro"
			(at 355.6 198.12 0)
			(effects
				(font
					(size 1.27 1.27)
					(thickness 0.15)
				)
				(justify left bottom)
				(hide yes)
			)
		)
		(property "License" "Apache-2.0"
			(at 355.6 200.66 0)
			(effects
				(font
					(size 1.27 1.27)
					(thickness 0.15)
				)
				(justify left bottom)
				(hide yes)
			)
		)
		(property "DNP" "DNP"
			(at 340.36 179.07 0)
			(effects
				(font
					(size 1.27 1.27)
				)
			)
		)
		(pin "1"
		)
		(pin "2"
		)
		(instances
			(project "k410t-devboard"
				(path ""
					(reference "D17")
					(unit 1)
				)
			)
		)
	)
	(symbol
		(lib_id "antmicropower:VDC")
		(at 392.43 33.02 0)
		(unit 1)
		(exclude_from_sim no)
		(in_bom yes)
		(on_board yes)
		(dnp no)
		(fields_autoplaced yes)
		(property "Reference" "#PWR0113"
			(at 392.43 35.56 0)
			(effects
				(font
					(size 1.27 1.27)
				)
				(hide yes)
			)
		)
		(property "Value" "VDC"
			(at 392.43 27.94 0)
			(effects
				(font
					(size 1.27 1.27)
				)
			)
		)
		(property "Footprint" ""
			(at 392.43 33.02 0)
			(effects
				(font
					(size 1.27 1.27)
				)
				(hide yes)
			)
		)
		(property "Datasheet" ""
			(at 392.43 33.02 0)
			(effects
				(font
					(size 1.27 1.27)
				)
				(hide yes)
			)
		)
		(property "Description" ""
			(at 392.43 33.02 0)
			(effects
				(font
					(size 1.27 1.27)
				)
			)
		)
		(pin "1"
		)
		(instances
			(project "k410t-devboard"
				(path ""
					(reference "#PWR0113")
					(unit 1)
				)
			)
		)
	)
	(symbol
		(lib_id "antmicropower:GND")
		(at 146.05 158.75 0)
		(unit 1)
		(exclude_from_sim no)
		(in_bom yes)
		(on_board yes)
		(dnp no)
		(property "Reference" "#PWR091"
			(at 146.05 165.1 0)
			(effects
				(font
					(size 1.27 1.27)
				)
				(hide yes)
			)
		)
		(property "Value" "GND"
			(at 146.05 162.56 0)
			(effects
				(font
					(size 1.27 1.27)
				)
			)
		)
		(property "Footprint" ""
			(at 154.94 166.37 0)
			(effects
				(font
					(size 1.27 1.27)
					(thickness 0.15)
				)
				(justify left bottom)
				(hide yes)
			)
		)
		(property "Datasheet" ""
			(at 154.94 171.45 0)
			(effects
				(font
					(size 1.27 1.27)
					(thickness 0.15)
				)
				(justify left bottom)
				(hide yes)
			)
		)
		(property "Description" ""
			(at 146.05 158.75 0)
			(effects
				(font
					(size 1.27 1.27)
				)
			)
		)
		(property "Author" "Antmicro"
			(at 154.94 166.37 0)
			(effects
				(font
					(size 1.27 1.27)
					(thickness 0.15)
				)
				(justify left bottom)
				(hide yes)
			)
		)
		(property "License" "Apache-2.0"
			(at 154.94 168.91 0)
			(effects
				(font
					(size 1.27 1.27)
					(thickness 0.15)
				)
				(justify left bottom)
				(hide yes)
			)
		)
		(pin "1"
		)
		(instances
			(project "k410t-devboard"
				(path ""
					(reference "#PWR091")
					(unit 1)
				)
			)
		)
	)
	(symbol
		(lib_id "antmicropower:GND")
		(at 90.17 97.79 0)
		(unit 1)
		(exclude_from_sim no)
		(in_bom yes)
		(on_board yes)
		(dnp no)
		(property "Reference" "#PWR089"
			(at 90.17 104.14 0)
			(effects
				(font
					(size 1.27 1.27)
				)
				(hide yes)
			)
		)
		(property "Value" "GND"
			(at 90.17 101.6 0)
			(effects
				(font
					(size 1.27 1.27)
				)
			)
		)
		(property "Footprint" ""
			(at 99.06 105.41 0)
			(effects
				(font
					(size 1.27 1.27)
					(thickness 0.15)
				)
				(justify left bottom)
				(hide yes)
			)
		)
		(property "Datasheet" ""
			(at 99.06 110.49 0)
			(effects
				(font
					(size 1.27 1.27)
					(thickness 0.15)
				)
				(justify left bottom)
				(hide yes)
			)
		)
		(property "Description" ""
			(at 90.17 97.79 0)
			(effects
				(font
					(size 1.27 1.27)
				)
			)
		)
		(property "Author" "Antmicro"
			(at 99.06 105.41 0)
			(effects
				(font
					(size 1.27 1.27)
					(thickness 0.15)
				)
				(justify left bottom)
				(hide yes)
			)
		)
		(property "License" "Apache-2.0"
			(at 99.06 107.95 0)
			(effects
				(font
					(size 1.27 1.27)
					(thickness 0.15)
				)
				(justify left bottom)
				(hide yes)
			)
		)
		(pin "1"
		)
		(instances
			(project "k410t-devboard"
				(path ""
					(reference "#PWR089")
					(unit 1)
				)
			)
		)
	)
	(symbol
		(lib_id "antmicroResistors0402:R_0R_0402")
		(at 195.58 241.3 90)
		(unit 1)
		(exclude_from_sim no)
		(in_bom no)
		(on_board yes)
		(dnp yes)
		(property "Reference" "R39"
			(at 196.85 237.49 90)
			(effects
				(font
					(size 1.27 1.27)
				)
				(justify right)
			)
		)
		(property "Value" "R_0R_0402"
			(at 208.28 220.98 0)
			(effects
				(font
					(size 1.27 1.27)
					(thickness 0.15)
				)
				(justify left bottom)
				(hide yes)
			)
		)
		(property "Footprint" "antmicro-footprints:R_0402_1005Metric"
			(at 210.82 220.98 0)
			(effects
				(font
					(size 1.27 1.27)
					(thickness 0.15)
				)
				(justify left bottom)
				(hide yes)
			)
		)
		(property "Datasheet" "https://industrial.panasonic.com/cdbs/www-data/pdf/RDA0000/AOA0000C301.pdf"
			(at 213.36 220.98 0)
			(effects
				(font
					(size 1.27 1.27)
					(thickness 0.15)
				)
				(justify left bottom)
				(hide yes)
			)
		)
		(property "Description" ""
			(at 195.58 241.3 0)
			(effects
				(font
					(size 1.27 1.27)
				)
			)
		)
		(property "Manufacturer" "Panasonic"
			(at 218.44 220.98 0)
			(effects
				(font
					(size 1.27 1.27)
					(thickness 0.15)
				)
				(justify left bottom)
				(hide yes)
			)
		)
		(property "MPN" "ERJ2GE0R00X"
			(at 215.9 220.98 0)
			(effects
				(font
					(size 1.27 1.27)
					(thickness 0.15)
				)
				(justify left bottom)
				(hide yes)
			)
		)
		(property "Val" "0R"
			(at 196.85 240.03 90)
			(effects
				(font
					(size 1.27 1.27)
					(thickness 0.15)
				)
				(justify right)
			)
		)
		(property "DNP" "DNP"
			(at 195.58 236.855 0)
			(effects
				(font
					(size 1.27 1.27)
				)
				(justify right)
			)
		)
		(property "License" "Apache-2.0"
			(at 220.98 220.98 0)
			(effects
				(font
					(size 1.27 1.27)
					(thickness 0.15)
				)
				(justify left bottom)
				(hide yes)
			)
		)
		(property "Author" "Antmicro"
			(at 223.52 220.98 0)
			(effects
				(font
					(size 1.27 1.27)
					(thickness 0.15)
				)
				(justify left bottom)
				(hide yes)
			)
		)
		(property "Tolerance" "~"
			(at 205.74 220.98 0)
			(effects
				(font
					(size 1.27 1.27)
				)
				(justify left bottom)
				(hide yes)
			)
		)
		(property "Current" "1A"
			(at 198.12 242.5699 90)
			(effects
				(font
					(size 1.27 1.27)
					(thickness 0.15)
				)
				(justify right)
				(hide yes)
			)
		)
		(pin "1"
		)
		(pin "2"
		)
		(instances
			(project "k410t-devboard"
				(path ""
					(reference "R39")
					(unit 1)
				)
			)
		)
	)
)
